(kicad_sch
	(version 20250114)
	(generator "eeschema")
	(generator_version "9.0")
	(paper "A3")
	(title_block
		(title "SDI-MIPI Video Converter")
		(date "2023-10-12")
		(rev "1.1.4")
		(comment 1 "www.antmicro.com")
		(comment 2 "Antmicro Ltd.")
	)
	(text "Cable driver"
		(exclude_from_sim no)
		(at 240.03 19.05 0)
		(effects
			(font
				(size 4 4)
			)
			(justify left bottom)
		)
	)
	(text "FPGA\n"
		(exclude_from_sim no)
		(at 13.97 20.32 0)
		(effects
			(font
				(size 4 4)
			)
			(justify left bottom)
		)
	)
	(text "SDI Receiver"
		(exclude_from_sim no)
		(at 12.7 153.67 0)
		(effects
			(font
				(size 4 4)
			)
			(justify left bottom)
		)
	)
	(junction
		(at 259.08 210.82)
		(diameter 0)
		(color 0 0 0 0)
	)
	(junction
		(at 259.08 250.19)
		(diameter 0)
		(color 0 0 0 0)
	)
	(junction
		(at 299.72 86.36)
		(diameter 0)
		(color 0 0 0 0)
	)
	(junction
		(at 69.85 182.88)
		(diameter 0)
		(color 0 0 0 0)
	)
	(junction
		(at 55.88 182.88)
		(diameter 0)
		(color 0 0 0 0)
	)
	(junction
		(at 318.77 205.74)
		(diameter 0)
		(color 0 0 0 0)
	)
	(junction
		(at 191.77 175.26)
		(diameter 0)
		(color 0 0 0 0)
	)
	(junction
		(at 299.72 78.74)
		(diameter 0)
		(color 0 0 0 0)
	)
	(junction
		(at 236.22 250.19)
		(diameter 0)
		(color 0 0 0 0)
	)
	(junction
		(at 318.77 213.36)
		(diameter 0)
		(color 0 0 0 0)
	)
	(junction
		(at 270.51 210.82)
		(diameter 0)
		(color 0 0 0 0)
	)
	(junction
		(at 115.57 106.68)
		(diameter 0)
		(color 0 0 0 0)
	)
	(junction
		(at 182.88 172.72)
		(diameter 0)
		(color 0 0 0 0)
	)
	(junction
		(at 259.08 185.42)
		(diameter 0)
		(color 0 0 0 0)
	)
	(junction
		(at 335.28 93.98)
		(diameter 0)
		(color 0 0 0 0)
	)
	(junction
		(at 247.65 210.82)
		(diameter 0)
		(color 0 0 0 0)
	)
	(junction
		(at 259.08 231.14)
		(diameter 0)
		(color 0 0 0 0)
	)
	(junction
		(at 314.96 78.74)
		(diameter 0)
		(color 0 0 0 0)
	)
	(junction
		(at 62.23 199.39)
		(diameter 0)
		(color 0 0 0 0)
	)
	(junction
		(at 184.15 172.72)
		(diameter 0)
		(color 0 0 0 0)
	)
	(junction
		(at 314.96 82.55)
		(diameter 0)
		(color 0 0 0 0)
	)
	(junction
		(at 212.09 63.5)
		(diameter 0)
		(color 0 0 0 0)
	)
	(junction
		(at 270.51 250.19)
		(diameter 0)
		(color 0 0 0 0)
	)
	(junction
		(at 247.65 231.14)
		(diameter 0)
		(color 0 0 0 0)
	)
	(junction
		(at 118.11 24.13)
		(diameter 0)
		(color 0 0 0 0)
	)
	(junction
		(at 266.7 167.64)
		(diameter 0)
		(color 0 0 0 0)
	)
	(junction
		(at 322.58 93.98)
		(diameter 0)
		(color 0 0 0 0)
	)
	(junction
		(at 261.62 73.66)
		(diameter 0)
		(color 0 0 0 0)
	)
	(junction
		(at 318.77 215.9)
		(diameter 0)
		(color 0 0 0 0)
	)
	(junction
		(at 318.77 208.28)
		(diameter 0)
		(color 0 0 0 0)
	)
	(junction
		(at 270.51 185.42)
		(diameter 0)
		(color 0 0 0 0)
	)
	(junction
		(at 50.8 199.39)
		(diameter 0)
		(color 0 0 0 0)
	)
	(junction
		(at 262.89 96.52)
		(diameter 0)
		(color 0 0 0 0)
	)
	(junction
		(at 247.65 185.42)
		(diameter 0)
		(color 0 0 0 0)
	)
	(junction
		(at 101.6 193.04)
		(diameter 0)
		(color 0 0 0 0)
	)
	(junction
		(at 115.57 167.64)
		(diameter 0)
		(color 0 0 0 0)
	)
	(junction
		(at 69.85 172.72)
		(diameter 0)
		(color 0 0 0 0)
	)
	(junction
		(at 318.77 218.44)
		(diameter 0)
		(color 0 0 0 0)
	)
	(junction
		(at 262.89 99.06)
		(diameter 0)
		(color 0 0 0 0)
	)
	(junction
		(at 247.65 250.19)
		(diameter 0)
		(color 0 0 0 0)
	)
	(junction
		(at 190.5 175.26)
		(diameter 0)
		(color 0 0 0 0)
	)
	(junction
		(at 284.48 210.82)
		(diameter 0)
		(color 0 0 0 0)
	)
	(junction
		(at 270.51 231.14)
		(diameter 0)
		(color 0 0 0 0)
	)
	(junction
		(at 60.96 199.39)
		(diameter 0)
		(color 0 0 0 0)
	)
	(junction
		(at 318.77 210.82)
		(diameter 0)
		(color 0 0 0 0)
	)
	(wire
		(pts
			(xy 299.72 86.36) (xy 299.72 83.82)
		)
		(stroke
			(width 0)
			(type default)
		)
	)
	(wire
		(pts
			(xy 58.42 199.39) (xy 60.96 199.39)
		)
		(stroke
			(width 0)
			(type default)
		)
	)
	(wire
		(pts
			(xy 262.89 96.52) (xy 262.89 99.06)
		)
		(stroke
			(width 0)
			(type default)
		)
	)
	(wire
		(pts
			(xy 85.09 259.08) (xy 93.98 259.08)
		)
		(stroke
			(width 0)
			(type default)
		)
	)
	(wire
		(pts
			(xy 76.2 176.53) (xy 83.82 176.53)
		)
		(stroke
			(width 0)
			(type default)
		)
	)
	(wire
		(pts
			(xy 196.85 78.74) (xy 180.34 78.74)
		)
		(stroke
			(width 0)
			(type default)
		)
	)
	(wire
		(pts
			(xy 120.65 271.78) (xy 130.81 271.78)
		)
		(stroke
			(width 0)
			(type default)
		)
	)
	(wire
		(pts
			(xy 85.09 256.54) (xy 93.98 256.54)
		)
		(stroke
			(width 0)
			(type default)
		)
	)
	(wire
		(pts
			(xy 110.49 116.84) (xy 96.52 116.84)
		)
		(stroke
			(width 0)
			(type default)
		)
	)
	(wire
		(pts
			(xy 196.85 88.9) (xy 180.34 88.9)
		)
		(stroke
			(width 0)
			(type default)
		)
	)
	(wire
		(pts
			(xy 284.48 213.36) (xy 289.56 213.36)
		)
		(stroke
			(width 0)
			(type default)
		)
	)
	(wire
		(pts
			(xy 151.13 248.92) (xy 151.13 251.46)
		)
		(stroke
			(width 0)
			(type default)
		)
	)
	(wire
		(pts
			(xy 182.88 172.72) (xy 184.15 172.72)
		)
		(stroke
			(width 0)
			(type default)
		)
	)
	(wire
		(pts
			(xy 92.71 170.18) (xy 92.71 167.64)
		)
		(stroke
			(width 0)
			(type default)
		)
	)
	(wire
		(pts
			(xy 314.96 78.74) (xy 314.96 82.55)
		)
		(stroke
			(width 0)
			(type default)
		)
	)
	(wire
		(pts
			(xy 270.51 250.19) (xy 270.51 251.46)
		)
		(stroke
			(width 0)
			(type default)
		)
	)
	(wire
		(pts
			(xy 96.52 201.93) (xy 96.52 204.47)
		)
		(stroke
			(width 0)
			(type default)
		)
	)
	(wire
		(pts
			(xy 151.13 187.96) (xy 168.91 187.96)
		)
		(stroke
			(width 0)
			(type default)
		)
	)
	(wire
		(pts
			(xy 106.68 39.37) (xy 96.52 39.37)
		)
		(stroke
			(width 0)
			(type default)
		)
	)
	(wire
		(pts
			(xy 85.09 271.78) (xy 93.98 271.78)
		)
		(stroke
			(width 0)
			(type default)
		)
	)
	(wire
		(pts
			(xy 270.51 185.42) (xy 270.51 186.69)
		)
		(stroke
			(width 0)
			(type default)
		)
	)
	(wire
		(pts
			(xy 314.96 82.55) (xy 317.5 82.55)
		)
		(stroke
			(width 0)
			(type default)
		)
	)
	(wire
		(pts
			(xy 247.65 250.19) (xy 247.65 251.46)
		)
		(stroke
			(width 0)
			(type default)
		)
	)
	(wire
		(pts
			(xy 151.13 167.64) (xy 168.91 167.64)
		)
		(stroke
			(width 0)
			(type default)
		)
	)
	(wire
		(pts
			(xy 106.68 74.93) (xy 96.52 74.93)
		)
		(stroke
			(width 0)
			(type default)
		)
	)
	(wire
		(pts
			(xy 299.72 78.74) (xy 299.72 69.85)
		)
		(stroke
			(width 0)
			(type default)
		)
	)
	(wire
		(pts
			(xy 73.66 208.28) (xy 73.66 204.47)
		)
		(stroke
			(width 0)
			(type default)
		)
	)
	(wire
		(pts
			(xy 262.89 99.06) (xy 264.16 99.06)
		)
		(stroke
			(width 0)
			(type default)
		)
	)
	(wire
		(pts
			(xy 96.52 106.68) (xy 115.57 106.68)
		)
		(stroke
			(width 0)
			(type default)
		)
	)
	(wire
		(pts
			(xy 270.51 231.14) (xy 259.08 231.14)
		)
		(stroke
			(width 0)
			(type default)
		)
	)
	(wire
		(pts
			(xy 322.58 99.06) (xy 322.58 93.98)
		)
		(stroke
			(width 0)
			(type default)
		)
	)
	(wire
		(pts
			(xy 259.08 217.17) (xy 259.08 218.44)
		)
		(stroke
			(width 0)
			(type default)
		)
	)
	(wire
		(pts
			(xy 85.09 251.46) (xy 93.98 251.46)
		)
		(stroke
			(width 0)
			(type default)
		)
	)
	(wire
		(pts
			(xy 85.09 238.76) (xy 93.98 238.76)
		)
		(stroke
			(width 0)
			(type default)
		)
	)
	(wire
		(pts
			(xy 247.65 256.54) (xy 247.65 257.81)
		)
		(stroke
			(width 0)
			(type default)
		)
	)
	(wire
		(pts
			(xy 111.76 167.64) (xy 115.57 167.64)
		)
		(stroke
			(width 0)
			(type default)
		)
	)
	(wire
		(pts
			(xy 109.22 177.8) (xy 119.38 177.8)
		)
		(stroke
			(width 0)
			(type default)
		)
	)
	(wire
		(pts
			(xy 120.65 242.57) (xy 151.13 242.57)
		)
		(stroke
			(width 0)
			(type default)
		)
	)
	(wire
		(pts
			(xy 236.22 256.54) (xy 236.22 257.81)
		)
		(stroke
			(width 0)
			(type default)
		)
	)
	(wire
		(pts
			(xy 85.09 266.7) (xy 93.98 266.7)
		)
		(stroke
			(width 0)
			(type default)
		)
	)
	(wire
		(pts
			(xy 316.23 208.28) (xy 318.77 208.28)
		)
		(stroke
			(width 0)
			(type default)
		)
	)
	(wire
		(pts
			(xy 262.89 96.52) (xy 264.16 96.52)
		)
		(stroke
			(width 0)
			(type default)
		)
	)
	(wire
		(pts
			(xy 151.13 198.12) (xy 168.91 198.12)
		)
		(stroke
			(width 0)
			(type default)
		)
	)
	(wire
		(pts
			(xy 184.15 158.75) (xy 184.15 160.02)
		)
		(stroke
			(width 0)
			(type default)
		)
	)
	(wire
		(pts
			(xy 322.58 99.06) (xy 326.39 99.06)
		)
		(stroke
			(width 0)
			(type default)
		)
	)
	(wire
		(pts
			(xy 151.13 172.72) (xy 182.88 172.72)
		)
		(stroke
			(width 0)
			(type default)
		)
	)
	(wire
		(pts
			(xy 85.09 254) (xy 93.98 254)
		)
		(stroke
			(width 0)
			(type default)
		)
	)
	(wire
		(pts
			(xy 151.13 177.8) (xy 168.91 177.8)
		)
		(stroke
			(width 0)
			(type default)
		)
	)
	(wire
		(pts
			(xy 318.77 213.36) (xy 318.77 215.9)
		)
		(stroke
			(width 0)
			(type default)
		)
	)
	(wire
		(pts
			(xy 110.49 124.46) (xy 96.52 124.46)
		)
		(stroke
			(width 0)
			(type default)
		)
	)
	(wire
		(pts
			(xy 247.65 83.82) (xy 264.16 83.82)
		)
		(stroke
			(width 0)
			(type default)
		)
	)
	(wire
		(pts
			(xy 85.09 236.22) (xy 93.98 236.22)
		)
		(stroke
			(width 0)
			(type default)
		)
	)
	(wire
		(pts
			(xy 190.5 158.75) (xy 190.5 160.02)
		)
		(stroke
			(width 0)
			(type default)
		)
	)
	(wire
		(pts
			(xy 73.66 213.36) (xy 73.66 214.63)
		)
		(stroke
			(width 0)
			(type default)
		)
	)
	(wire
		(pts
			(xy 106.68 85.09) (xy 96.52 85.09)
		)
		(stroke
			(width 0)
			(type default)
		)
	)
	(wire
		(pts
			(xy 110.49 111.76) (xy 96.52 111.76)
		)
		(stroke
			(width 0)
			(type default)
		)
	)
	(wire
		(pts
			(xy 55.88 182.88) (xy 55.88 184.15)
		)
		(stroke
			(width 0)
			(type default)
		)
	)
	(wire
		(pts
			(xy 106.68 41.91) (xy 96.52 41.91)
		)
		(stroke
			(width 0)
			(type default)
		)
	)
	(wire
		(pts
			(xy 85.09 264.16) (xy 93.98 264.16)
		)
		(stroke
			(width 0)
			(type default)
		)
	)
	(wire
		(pts
			(xy 318.77 208.28) (xy 318.77 210.82)
		)
		(stroke
			(width 0)
			(type default)
		)
	)
	(wire
		(pts
			(xy 247.65 81.28) (xy 264.16 81.28)
		)
		(stroke
			(width 0)
			(type default)
		)
	)
	(wire
		(pts
			(xy 270.51 210.82) (xy 284.48 210.82)
		)
		(stroke
			(width 0)
			(type default)
		)
	)
	(wire
		(pts
			(xy 106.68 49.53) (xy 96.52 49.53)
		)
		(stroke
			(width 0)
			(type default)
		)
	)
	(wire
		(pts
			(xy 106.68 34.29) (xy 96.52 34.29)
		)
		(stroke
			(width 0)
			(type default)
		)
	)
	(wire
		(pts
			(xy 264.16 73.66) (xy 261.62 73.66)
		)
		(stroke
			(width 0)
			(type default)
		)
	)
	(wire
		(pts
			(xy 259.08 250.19) (xy 270.51 250.19)
		)
		(stroke
			(width 0)
			(type default)
		)
	)
	(wire
		(pts
			(xy 110.49 109.22) (xy 96.52 109.22)
		)
		(stroke
			(width 0)
			(type default)
		)
	)
	(wire
		(pts
			(xy 236.22 248.92) (xy 236.22 250.19)
		)
		(stroke
			(width 0)
			(type default)
		)
	)
	(wire
		(pts
			(xy 110.49 121.92) (xy 96.52 121.92)
		)
		(stroke
			(width 0)
			(type default)
		)
	)
	(wire
		(pts
			(xy 85.09 241.3) (xy 93.98 241.3)
		)
		(stroke
			(width 0)
			(type default)
		)
	)
	(wire
		(pts
			(xy 318.77 205.74) (xy 318.77 208.28)
		)
		(stroke
			(width 0)
			(type default)
		)
	)
	(wire
		(pts
			(xy 106.68 82.55) (xy 96.52 82.55)
		)
		(stroke
			(width 0)
			(type default)
		)
	)
	(wire
		(pts
			(xy 106.68 26.67) (xy 96.52 26.67)
		)
		(stroke
			(width 0)
			(type default)
		)
	)
	(polyline
		(pts
			(xy 12.7 146.05) (xy 407.67 146.05)
		)
		(stroke
			(width 0)
			(type default)
		)
	)
	(wire
		(pts
			(xy 190.5 175.26) (xy 191.77 175.26)
		)
		(stroke
			(width 0)
			(type default)
		)
	)
	(wire
		(pts
			(xy 334.01 69.85) (xy 339.09 69.85)
		)
		(stroke
			(width 0)
			(type default)
		)
	)
	(wire
		(pts
			(xy 289.56 205.74) (xy 284.48 205.74)
		)
		(stroke
			(width 0)
			(type default)
		)
	)
	(wire
		(pts
			(xy 195.58 96.52) (xy 180.34 96.52)
		)
		(stroke
			(width 0)
			(type default)
		)
	)
	(wire
		(pts
			(xy 151.13 170.18) (xy 168.91 170.18)
		)
		(stroke
			(width 0)
			(type default)
		)
	)
	(wire
		(pts
			(xy 106.68 67.31) (xy 96.52 67.31)
		)
		(stroke
			(width 0)
			(type default)
		)
	)
	(wire
		(pts
			(xy 118.11 24.13) (xy 118.11 20.32)
		)
		(stroke
			(width 0)
			(type default)
		)
	)
	(wire
		(pts
			(xy 85.09 248.92) (xy 93.98 248.92)
		)
		(stroke
			(width 0)
			(type default)
		)
	)
	(wire
		(pts
			(xy 287.02 81.28) (xy 299.72 81.28)
		)
		(stroke
			(width 0)
			(type default)
		)
	)
	(wire
		(pts
			(xy 247.65 231.14) (xy 247.65 229.87)
		)
		(stroke
			(width 0)
			(type default)
		)
	)
	(wire
		(pts
			(xy 76.2 172.72) (xy 76.2 176.53)
		)
		(stroke
			(width 0)
			(type default)
		)
	)
	(wire
		(pts
			(xy 299.72 78.74) (xy 299.72 81.28)
		)
		(stroke
			(width 0)
			(type default)
		)
	)
	(wire
		(pts
			(xy 64.77 172.72) (xy 69.85 172.72)
		)
		(stroke
			(width 0)
			(type default)
		)
	)
	(wire
		(pts
			(xy 289.56 71.12) (xy 289.56 72.39)
		)
		(stroke
			(width 0)
			(type default)
		)
	)
	(wire
		(pts
			(xy 101.6 190.5) (xy 101.6 193.04)
		)
		(stroke
			(width 0)
			(type default)
		)
	)
	(wire
		(pts
			(xy 151.13 203.2) (xy 168.91 203.2)
		)
		(stroke
			(width 0)
			(type default)
		)
	)
	(wire
		(pts
			(xy 132.08 226.06) (xy 120.65 226.06)
		)
		(stroke
			(width 0)
			(type default)
		)
	)
	(wire
		(pts
			(xy 96.52 179.07) (xy 96.52 180.34)
		)
		(stroke
			(width 0)
			(type default)
		)
	)
	(wire
		(pts
			(xy 106.68 44.45) (xy 96.52 44.45)
		)
		(stroke
			(width 0)
			(type default)
		)
	)
	(wire
		(pts
			(xy 182.88 172.72) (xy 182.88 180.34)
		)
		(stroke
			(width 0)
			(type default)
		)
	)
	(wire
		(pts
			(xy 247.65 209.55) (xy 247.65 210.82)
		)
		(stroke
			(width 0)
			(type default)
		)
	)
	(wire
		(pts
			(xy 190.5 165.1) (xy 190.5 175.26)
		)
		(stroke
			(width 0)
			(type default)
		)
	)
	(wire
		(pts
			(xy 115.57 163.83) (xy 115.57 167.64)
		)
		(stroke
			(width 0)
			(type default)
		)
	)
	(wire
		(pts
			(xy 261.62 73.66) (xy 261.62 74.93)
		)
		(stroke
			(width 0)
			(type default)
		)
	)
	(wire
		(pts
			(xy 151.13 190.5) (xy 168.91 190.5)
		)
		(stroke
			(width 0)
			(type default)
		)
	)
	(wire
		(pts
			(xy 326.39 69.85) (xy 328.93 69.85)
		)
		(stroke
			(width 0)
			(type default)
		)
	)
	(wire
		(pts
			(xy 62.23 213.36) (xy 62.23 214.63)
		)
		(stroke
			(width 0)
			(type default)
		)
	)
	(wire
		(pts
			(xy 151.13 180.34) (xy 168.91 180.34)
		)
		(stroke
			(width 0)
			(type default)
		)
	)
	(wire
		(pts
			(xy 270.51 191.77) (xy 270.51 193.04)
		)
		(stroke
			(width 0)
			(type default)
		)
	)
	(wire
		(pts
			(xy 55.88 182.88) (xy 59.69 182.88)
		)
		(stroke
			(width 0)
			(type default)
		)
	)
	(wire
		(pts
			(xy 331.47 99.06) (xy 335.28 99.06)
		)
		(stroke
			(width 0)
			(type default)
		)
	)
	(wire
		(pts
			(xy 60.96 199.39) (xy 62.23 199.39)
		)
		(stroke
			(width 0)
			(type default)
		)
	)
	(wire
		(pts
			(xy 247.65 237.49) (xy 247.65 238.76)
		)
		(stroke
			(width 0)
			(type default)
		)
	)
	(wire
		(pts
			(xy 92.71 167.64) (xy 106.68 167.64)
		)
		(stroke
			(width 0)
			(type default)
		)
	)
	(wire
		(pts
			(xy 151.13 175.26) (xy 190.5 175.26)
		)
		(stroke
			(width 0)
			(type default)
		)
	)
	(wire
		(pts
			(xy 58.42 194.31) (xy 60.96 194.31)
		)
		(stroke
			(width 0)
			(type default)
		)
	)
	(wire
		(pts
			(xy 106.68 29.21) (xy 96.52 29.21)
		)
		(stroke
			(width 0)
			(type default)
		)
	)
	(wire
		(pts
			(xy 106.68 87.63) (xy 96.52 87.63)
		)
		(stroke
			(width 0)
			(type default)
		)
	)
	(wire
		(pts
			(xy 162.56 248.92) (xy 162.56 251.46)
		)
		(stroke
			(width 0)
			(type default)
		)
	)
	(wire
		(pts
			(xy 106.68 46.99) (xy 96.52 46.99)
		)
		(stroke
			(width 0)
			(type default)
		)
	)
	(wire
		(pts
			(xy 299.72 78.74) (xy 304.8 78.74)
		)
		(stroke
			(width 0)
			(type default)
		)
	)
	(wire
		(pts
			(xy 115.57 167.64) (xy 119.38 167.64)
		)
		(stroke
			(width 0)
			(type default)
		)
	)
	(wire
		(pts
			(xy 288.29 218.44) (xy 288.29 250.19)
		)
		(stroke
			(width 0)
			(type default)
		)
	)
	(wire
		(pts
			(xy 196.85 86.36) (xy 180.34 86.36)
		)
		(stroke
			(width 0)
			(type default)
		)
	)
	(wire
		(pts
			(xy 259.08 185.42) (xy 247.65 185.42)
		)
		(stroke
			(width 0)
			(type default)
		)
	)
	(wire
		(pts
			(xy 184.15 165.1) (xy 184.15 172.72)
		)
		(stroke
			(width 0)
			(type default)
		)
	)
	(wire
		(pts
			(xy 309.88 78.74) (xy 314.96 78.74)
		)
		(stroke
			(width 0)
			(type default)
		)
	)
	(wire
		(pts
			(xy 264.16 77.47) (xy 264.16 73.66)
		)
		(stroke
			(width 0)
			(type default)
		)
	)
	(wire
		(pts
			(xy 106.68 72.39) (xy 96.52 72.39)
		)
		(stroke
			(width 0)
			(type default)
		)
	)
	(wire
		(pts
			(xy 115.57 106.68) (xy 115.57 110.49)
		)
		(stroke
			(width 0)
			(type default)
		)
	)
	(wire
		(pts
			(xy 106.68 57.15) (xy 96.52 57.15)
		)
		(stroke
			(width 0)
			(type default)
		)
	)
	(wire
		(pts
			(xy 115.57 115.57) (xy 115.57 116.84)
		)
		(stroke
			(width 0)
			(type default)
		)
	)
	(wire
		(pts
			(xy 119.38 170.18) (xy 96.52 170.18)
		)
		(stroke
			(width 0)
			(type default)
		)
	)
	(wire
		(pts
			(xy 110.49 114.3) (xy 96.52 114.3)
		)
		(stroke
			(width 0)
			(type default)
		)
	)
	(wire
		(pts
			(xy 354.33 93.98) (xy 365.76 93.98)
		)
		(stroke
			(width 0)
			(type default)
		)
	)
	(wire
		(pts
			(xy 180.34 63.5) (xy 212.09 63.5)
		)
		(stroke
			(width 0)
			(type default)
		)
	)
	(wire
		(pts
			(xy 110.49 119.38) (xy 96.52 119.38)
		)
		(stroke
			(width 0)
			(type default)
		)
	)
	(wire
		(pts
			(xy 247.65 210.82) (xy 247.65 212.09)
		)
		(stroke
			(width 0)
			(type default)
		)
	)
	(wire
		(pts
			(xy 259.08 231.14) (xy 247.65 231.14)
		)
		(stroke
			(width 0)
			(type default)
		)
	)
	(wire
		(pts
			(xy 331.47 93.98) (xy 335.28 93.98)
		)
		(stroke
			(width 0)
			(type default)
		)
	)
	(wire
		(pts
			(xy 316.23 215.9) (xy 318.77 215.9)
		)
		(stroke
			(width 0)
			(type default)
		)
	)
	(wire
		(pts
			(xy 247.65 185.42) (xy 247.65 184.15)
		)
		(stroke
			(width 0)
			(type default)
		)
	)
	(wire
		(pts
			(xy 196.85 81.28) (xy 180.34 81.28)
		)
		(stroke
			(width 0)
			(type default)
		)
	)
	(wire
		(pts
			(xy 284.48 215.9) (xy 284.48 231.14)
		)
		(stroke
			(width 0)
			(type default)
		)
	)
	(wire
		(pts
			(xy 259.08 237.49) (xy 259.08 238.76)
		)
		(stroke
			(width 0)
			(type default)
		)
	)
	(wire
		(pts
			(xy 118.11 182.88) (xy 119.38 182.88)
		)
		(stroke
			(width 0)
			(type default)
		)
	)
	(wire
		(pts
			(xy 101.6 190.5) (xy 104.14 190.5)
		)
		(stroke
			(width 0)
			(type default)
		)
	)
	(wire
		(pts
			(xy 247.65 191.77) (xy 247.65 193.04)
		)
		(stroke
			(width 0)
			(type default)
		)
	)
	(wire
		(pts
			(xy 106.68 69.85) (xy 96.52 69.85)
		)
		(stroke
			(width 0)
			(type default)
		)
	)
	(wire
		(pts
			(xy 236.22 250.19) (xy 236.22 251.46)
		)
		(stroke
			(width 0)
			(type default)
		)
	)
	(wire
		(pts
			(xy 106.68 80.01) (xy 96.52 80.01)
		)
		(stroke
			(width 0)
			(type default)
		)
	)
	(wire
		(pts
			(xy 85.09 243.84) (xy 93.98 243.84)
		)
		(stroke
			(width 0)
			(type default)
		)
	)
	(wire
		(pts
			(xy 314.96 77.47) (xy 314.96 78.74)
		)
		(stroke
			(width 0)
			(type default)
		)
	)
	(wire
		(pts
			(xy 102.87 179.07) (xy 102.87 180.34)
		)
		(stroke
			(width 0)
			(type default)
		)
	)
	(wire
		(pts
			(xy 119.38 193.04) (xy 101.6 193.04)
		)
		(stroke
			(width 0)
			(type default)
		)
	)
	(wire
		(pts
			(xy 261.62 80.01) (xy 261.62 92.71)
		)
		(stroke
			(width 0)
			(type default)
		)
	)
	(wire
		(pts
			(xy 292.1 88.9) (xy 287.02 88.9)
		)
		(stroke
			(width 0)
			(type default)
		)
	)
	(wire
		(pts
			(xy 55.88 182.88) (xy 55.88 172.72)
		)
		(stroke
			(width 0)
			(type default)
		)
	)
	(wire
		(pts
			(xy 132.08 229.87) (xy 120.65 229.87)
		)
		(stroke
			(width 0)
			(type default)
		)
	)
	(wire
		(pts
			(xy 289.56 208.28) (xy 284.48 208.28)
		)
		(stroke
			(width 0)
			(type default)
		)
	)
	(wire
		(pts
			(xy 132.08 240.03) (xy 120.65 240.03)
		)
		(stroke
			(width 0)
			(type default)
		)
	)
	(wire
		(pts
			(xy 85.09 269.24) (xy 93.98 269.24)
		)
		(stroke
			(width 0)
			(type default)
		)
	)
	(wire
		(pts
			(xy 270.51 231.14) (xy 270.51 232.41)
		)
		(stroke
			(width 0)
			(type default)
		)
	)
	(wire
		(pts
			(xy 69.85 173.99) (xy 69.85 172.72)
		)
		(stroke
			(width 0)
			(type default)
		)
	)
	(wire
		(pts
			(xy 151.13 195.58) (xy 168.91 195.58)
		)
		(stroke
			(width 0)
			(type default)
		)
	)
	(wire
		(pts
			(xy 236.22 250.19) (xy 247.65 250.19)
		)
		(stroke
			(width 0)
			(type default)
		)
	)
	(wire
		(pts
			(xy 88.9 204.47) (xy 96.52 204.47)
		)
		(stroke
			(width 0)
			(type default)
		)
	)
	(wire
		(pts
			(xy 96.52 132.08) (xy 110.49 132.08)
		)
		(stroke
			(width 0)
			(type default)
		)
	)
	(wire
		(pts
			(xy 38.1 199.39) (xy 50.8 199.39)
		)
		(stroke
			(width 0)
			(type default)
		)
	)
	(wire
		(pts
			(xy 195.58 93.98) (xy 180.34 93.98)
		)
		(stroke
			(width 0)
			(type default)
		)
	)
	(wire
		(pts
			(xy 196.85 66.04) (xy 180.34 66.04)
		)
		(stroke
			(width 0)
			(type default)
		)
	)
	(wire
		(pts
			(xy 110.49 127) (xy 96.52 127)
		)
		(stroke
			(width 0)
			(type default)
		)
	)
	(wire
		(pts
			(xy 270.51 237.49) (xy 270.51 238.76)
		)
		(stroke
			(width 0)
			(type default)
		)
	)
	(wire
		(pts
			(xy 292.1 97.79) (xy 292.1 88.9)
		)
		(stroke
			(width 0)
			(type default)
		)
	)
	(wire
		(pts
			(xy 212.09 73.66) (xy 212.09 72.39)
		)
		(stroke
			(width 0)
			(type default)
		)
	)
	(wire
		(pts
			(xy 289.56 218.44) (xy 288.29 218.44)
		)
		(stroke
			(width 0)
			(type default)
		)
	)
	(wire
		(pts
			(xy 335.28 93.98) (xy 335.28 99.06)
		)
		(stroke
			(width 0)
			(type default)
		)
	)
	(wire
		(pts
			(xy 247.65 87.63) (xy 264.16 87.63)
		)
		(stroke
			(width 0)
			(type default)
		)
	)
	(wire
		(pts
			(xy 110.49 129.54) (xy 96.52 129.54)
		)
		(stroke
			(width 0)
			(type default)
		)
	)
	(wire
		(pts
			(xy 96.52 24.13) (xy 118.11 24.13)
		)
		(stroke
			(width 0)
			(type default)
		)
	)
	(polyline
		(pts
			(xy 254 284.48) (xy 255.27 284.48)
		)
		(stroke
			(width 0)
			(type default)
		)
	)
	(wire
		(pts
			(xy 335.28 93.98) (xy 349.25 93.98)
		)
		(stroke
			(width 0)
			(type default)
		)
	)
	(wire
		(pts
			(xy 96.52 170.18) (xy 96.52 173.99)
		)
		(stroke
			(width 0)
			(type default)
		)
	)
	(wire
		(pts
			(xy 270.51 210.82) (xy 270.51 212.09)
		)
		(stroke
			(width 0)
			(type default)
		)
	)
	(wire
		(pts
			(xy 69.85 172.72) (xy 76.2 172.72)
		)
		(stroke
			(width 0)
			(type default)
		)
	)
	(wire
		(pts
			(xy 53.34 194.31) (xy 50.8 194.31)
		)
		(stroke
			(width 0)
			(type default)
		)
	)
	(wire
		(pts
			(xy 316.23 213.36) (xy 318.77 213.36)
		)
		(stroke
			(width 0)
			(type default)
		)
	)
	(wire
		(pts
			(xy 318.77 203.2) (xy 316.23 203.2)
		)
		(stroke
			(width 0)
			(type default)
		)
	)
	(wire
		(pts
			(xy 85.09 228.6) (xy 93.98 228.6)
		)
		(stroke
			(width 0)
			(type default)
		)
	)
	(wire
		(pts
			(xy 151.13 205.74) (xy 168.91 205.74)
		)
		(stroke
			(width 0)
			(type default)
		)
	)
	(wire
		(pts
			(xy 106.68 31.75) (xy 96.52 31.75)
		)
		(stroke
			(width 0)
			(type default)
		)
	)
	(wire
		(pts
			(xy 55.88 172.72) (xy 59.69 172.72)
		)
		(stroke
			(width 0)
			(type default)
		)
	)
	(wire
		(pts
			(xy 115.57 106.68) (xy 115.57 102.87)
		)
		(stroke
			(width 0)
			(type default)
		)
	)
	(wire
		(pts
			(xy 259.08 250.19) (xy 259.08 251.46)
		)
		(stroke
			(width 0)
			(type default)
		)
	)
	(wire
		(pts
			(xy 92.71 193.04) (xy 92.71 205.74)
		)
		(stroke
			(width 0)
			(type default)
		)
	)
	(wire
		(pts
			(xy 151.13 200.66) (xy 168.91 200.66)
		)
		(stroke
			(width 0)
			(type default)
		)
	)
	(wire
		(pts
			(xy 270.51 185.42) (xy 284.48 185.42)
		)
		(stroke
			(width 0)
			(type default)
		)
	)
	(wire
		(pts
			(xy 106.68 54.61) (xy 96.52 54.61)
		)
		(stroke
			(width 0)
			(type default)
		)
	)
	(wire
		(pts
			(xy 266.7 166.37) (xy 266.7 167.64)
		)
		(stroke
			(width 0)
			(type default)
		)
	)
	(wire
		(pts
			(xy 85.09 231.14) (xy 93.98 231.14)
		)
		(stroke
			(width 0)
			(type default)
		)
	)
	(wire
		(pts
			(xy 196.85 68.58) (xy 180.34 68.58)
		)
		(stroke
			(width 0)
			(type default)
		)
	)
	(wire
		(pts
			(xy 85.09 233.68) (xy 93.98 233.68)
		)
		(stroke
			(width 0)
			(type default)
		)
	)
	(wire
		(pts
			(xy 259.08 185.42) (xy 259.08 186.69)
		)
		(stroke
			(width 0)
			(type default)
		)
	)
	(wire
		(pts
			(xy 259.08 231.14) (xy 259.08 232.41)
		)
		(stroke
			(width 0)
			(type default)
		)
	)
	(wire
		(pts
			(xy 151.13 185.42) (xy 168.91 185.42)
		)
		(stroke
			(width 0)
			(type default)
		)
	)
	(wire
		(pts
			(xy 182.88 185.42) (xy 182.88 186.69)
		)
		(stroke
			(width 0)
			(type default)
		)
	)
	(wire
		(pts
			(xy 62.23 199.39) (xy 83.82 199.39)
		)
		(stroke
			(width 0)
			(type default)
		)
	)
	(wire
		(pts
			(xy 288.29 167.64) (xy 288.29 203.2)
		)
		(stroke
			(width 0)
			(type default)
		)
	)
	(wire
		(pts
			(xy 287.02 83.82) (xy 299.72 83.82)
		)
		(stroke
			(width 0)
			(type default)
		)
	)
	(wire
		(pts
			(xy 106.68 62.23) (xy 96.52 62.23)
		)
		(stroke
			(width 0)
			(type default)
		)
	)
	(wire
		(pts
			(xy 162.56 256.54) (xy 162.56 259.08)
		)
		(stroke
			(width 0)
			(type default)
		)
	)
	(wire
		(pts
			(xy 316.23 205.74) (xy 318.77 205.74)
		)
		(stroke
			(width 0)
			(type default)
		)
	)
	(wire
		(pts
			(xy 316.23 210.82) (xy 318.77 210.82)
		)
		(stroke
			(width 0)
			(type default)
		)
	)
	(wire
		(pts
			(xy 106.68 64.77) (xy 96.52 64.77)
		)
		(stroke
			(width 0)
			(type default)
		)
	)
	(wire
		(pts
			(xy 64.77 182.88) (xy 69.85 182.88)
		)
		(stroke
			(width 0)
			(type default)
		)
	)
	(wire
		(pts
			(xy 262.89 99.06) (xy 262.89 101.6)
		)
		(stroke
			(width 0)
			(type default)
		)
	)
	(wire
		(pts
			(xy 314.96 82.55) (xy 314.96 86.36)
		)
		(stroke
			(width 0)
			(type default)
		)
	)
	(wire
		(pts
			(xy 99.06 193.04) (xy 101.6 193.04)
		)
		(stroke
			(width 0)
			(type default)
		)
	)
	(wire
		(pts
			(xy 50.8 199.39) (xy 53.34 199.39)
		)
		(stroke
			(width 0)
			(type default)
		)
	)
	(wire
		(pts
			(xy 270.51 256.54) (xy 270.51 257.81)
		)
		(stroke
			(width 0)
			(type default)
		)
	)
	(wire
		(pts
			(xy 259.08 191.77) (xy 259.08 193.04)
		)
		(stroke
			(width 0)
			(type default)
		)
	)
	(wire
		(pts
			(xy 62.23 208.28) (xy 62.23 199.39)
		)
		(stroke
			(width 0)
			(type default)
		)
	)
	(wire
		(pts
			(xy 151.13 182.88) (xy 168.91 182.88)
		)
		(stroke
			(width 0)
			(type default)
		)
	)
	(wire
		(pts
			(xy 93.98 193.04) (xy 92.71 193.04)
		)
		(stroke
			(width 0)
			(type default)
		)
	)
	(wire
		(pts
			(xy 85.09 246.38) (xy 93.98 246.38)
		)
		(stroke
			(width 0)
			(type default)
		)
	)
	(wire
		(pts
			(xy 284.48 210.82) (xy 289.56 210.82)
		)
		(stroke
			(width 0)
			(type default)
		)
	)
	(wire
		(pts
			(xy 326.39 83.82) (xy 326.39 82.55)
		)
		(stroke
			(width 0)
			(type default)
		)
	)
	(wire
		(pts
			(xy 106.68 59.69) (xy 96.52 59.69)
		)
		(stroke
			(width 0)
			(type default)
		)
	)
	(wire
		(pts
			(xy 299.72 86.36) (xy 304.8 86.36)
		)
		(stroke
			(width 0)
			(type default)
		)
	)
	(wire
		(pts
			(xy 247.65 185.42) (xy 247.65 186.69)
		)
		(stroke
			(width 0)
			(type default)
		)
	)
	(wire
		(pts
			(xy 195.58 83.82) (xy 180.34 83.82)
		)
		(stroke
			(width 0)
			(type default)
		)
	)
	(wire
		(pts
			(xy 322.58 93.98) (xy 326.39 93.98)
		)
		(stroke
			(width 0)
			(type default)
		)
	)
	(wire
		(pts
			(xy 96.52 201.93) (xy 119.38 201.93)
		)
		(stroke
			(width 0)
			(type default)
		)
	)
	(wire
		(pts
			(xy 266.7 160.02) (xy 266.7 161.29)
		)
		(stroke
			(width 0)
			(type default)
		)
	)
	(wire
		(pts
			(xy 196.85 91.44) (xy 180.34 91.44)
		)
		(stroke
			(width 0)
			(type default)
		)
	)
	(wire
		(pts
			(xy 247.65 210.82) (xy 259.08 210.82)
		)
		(stroke
			(width 0)
			(type default)
		)
	)
	(wire
		(pts
			(xy 76.2 179.07) (xy 83.82 179.07)
		)
		(stroke
			(width 0)
			(type default)
		)
	)
	(wire
		(pts
			(xy 106.68 90.17) (xy 96.52 90.17)
		)
		(stroke
			(width 0)
			(type default)
		)
	)
	(wire
		(pts
			(xy 151.13 193.04) (xy 168.91 193.04)
		)
		(stroke
			(width 0)
			(type default)
		)
	)
	(wire
		(pts
			(xy 318.77 203.2) (xy 318.77 205.74)
		)
		(stroke
			(width 0)
			(type default)
		)
	)
	(wire
		(pts
			(xy 299.72 93.98) (xy 299.72 86.36)
		)
		(stroke
			(width 0)
			(type default)
		)
	)
	(wire
		(pts
			(xy 132.08 232.41) (xy 120.65 232.41)
		)
		(stroke
			(width 0)
			(type default)
		)
	)
	(wire
		(pts
			(xy 370.84 99.06) (xy 370.84 100.33)
		)
		(stroke
			(width 0)
			(type default)
		)
	)
	(wire
		(pts
			(xy 289.56 215.9) (xy 284.48 215.9)
		)
		(stroke
			(width 0)
			(type default)
		)
	)
	(wire
		(pts
			(xy 264.16 90.17) (xy 262.89 90.17)
		)
		(stroke
			(width 0)
			(type default)
		)
	)
	(wire
		(pts
			(xy 50.8 194.31) (xy 50.8 199.39)
		)
		(stroke
			(width 0)
			(type default)
		)
	)
	(wire
		(pts
			(xy 162.56 237.49) (xy 162.56 243.84)
		)
		(stroke
			(width 0)
			(type default)
		)
	)
	(wire
		(pts
			(xy 120.65 269.24) (xy 130.81 269.24)
		)
		(stroke
			(width 0)
			(type default)
		)
	)
	(wire
		(pts
			(xy 76.2 179.07) (xy 76.2 182.88)
		)
		(stroke
			(width 0)
			(type default)
		)
	)
	(wire
		(pts
			(xy 33.02 204.47) (xy 33.02 205.74)
		)
		(stroke
			(width 0)
			(type default)
		)
	)
	(wire
		(pts
			(xy 115.57 157.48) (xy 115.57 158.75)
		)
		(stroke
			(width 0)
			(type default)
		)
	)
	(wire
		(pts
			(xy 102.87 172.72) (xy 102.87 173.99)
		)
		(stroke
			(width 0)
			(type default)
		)
	)
	(wire
		(pts
			(xy 85.09 261.62) (xy 93.98 261.62)
		)
		(stroke
			(width 0)
			(type default)
		)
	)
	(wire
		(pts
			(xy 118.11 33.02) (xy 118.11 34.29)
		)
		(stroke
			(width 0)
			(type default)
		)
	)
	(wire
		(pts
			(xy 106.68 36.83) (xy 96.52 36.83)
		)
		(stroke
			(width 0)
			(type default)
		)
	)
	(wire
		(pts
			(xy 318.77 218.44) (xy 318.77 220.98)
		)
		(stroke
			(width 0)
			(type default)
		)
	)
	(wire
		(pts
			(xy 247.65 231.14) (xy 247.65 232.41)
		)
		(stroke
			(width 0)
			(type default)
		)
	)
	(wire
		(pts
			(xy 318.77 215.9) (xy 318.77 218.44)
		)
		(stroke
			(width 0)
			(type default)
		)
	)
	(wire
		(pts
			(xy 196.85 73.66) (xy 180.34 73.66)
		)
		(stroke
			(width 0)
			(type default)
		)
	)
	(wire
		(pts
			(xy 212.09 59.69) (xy 212.09 63.5)
		)
		(stroke
			(width 0)
			(type default)
		)
	)
	(wire
		(pts
			(xy 196.85 76.2) (xy 180.34 76.2)
		)
		(stroke
			(width 0)
			(type default)
		)
	)
	(wire
		(pts
			(xy 287.02 91.44) (xy 289.56 91.44)
		)
		(stroke
			(width 0)
			(type default)
		)
	)
	(wire
		(pts
			(xy 270.51 185.42) (xy 259.08 185.42)
		)
		(stroke
			(width 0)
			(type default)
		)
	)
	(wire
		(pts
			(xy 259.08 210.82) (xy 259.08 212.09)
		)
		(stroke
			(width 0)
			(type default)
		)
	)
	(wire
		(pts
			(xy 284.48 205.74) (xy 284.48 185.42)
		)
		(stroke
			(width 0)
			(type default)
		)
	)
	(wire
		(pts
			(xy 191.77 175.26) (xy 191.77 180.34)
		)
		(stroke
			(width 0)
			(type default)
		)
	)
	(wire
		(pts
			(xy 196.85 71.12) (xy 180.34 71.12)
		)
		(stroke
			(width 0)
			(type default)
		)
	)
	(wire
		(pts
			(xy 109.22 190.5) (xy 119.38 190.5)
		)
		(stroke
			(width 0)
			(type default)
		)
	)
	(wire
		(pts
			(xy 284.48 208.28) (xy 284.48 210.82)
		)
		(stroke
			(width 0)
			(type default)
		)
	)
	(wire
		(pts
			(xy 102.87 172.72) (xy 119.38 172.72)
		)
		(stroke
			(width 0)
			(type default)
		)
	)
	(wire
		(pts
			(xy 151.13 256.54) (xy 151.13 259.08)
		)
		(stroke
			(width 0)
			(type default)
		)
	)
	(wire
		(pts
			(xy 262.89 90.17) (xy 262.89 96.52)
		)
		(stroke
			(width 0)
			(type default)
		)
	)
	(wire
		(pts
			(xy 85.09 274.32) (xy 93.98 274.32)
		)
		(stroke
			(width 0)
			(type default)
		)
	)
	(wire
		(pts
			(xy 106.68 52.07) (xy 96.52 52.07)
		)
		(stroke
			(width 0)
			(type default)
		)
	)
	(wire
		(pts
			(xy 109.22 180.34) (xy 119.38 180.34)
		)
		(stroke
			(width 0)
			(type default)
		)
	)
	(wire
		(pts
			(xy 270.51 231.14) (xy 284.48 231.14)
		)
		(stroke
			(width 0)
			(type default)
		)
	)
	(wire
		(pts
			(xy 289.56 91.44) (xy 289.56 77.47)
		)
		(stroke
			(width 0)
			(type default)
		)
	)
	(wire
		(pts
			(xy 191.77 185.42) (xy 191.77 186.69)
		)
		(stroke
			(width 0)
			(type default)
		)
	)
	(wire
		(pts
			(xy 69.85 182.88) (xy 69.85 181.61)
		)
		(stroke
			(width 0)
			(type default)
		)
	)
	(wire
		(pts
			(xy 261.62 72.39) (xy 261.62 73.66)
		)
		(stroke
			(width 0)
			(type default)
		)
	)
	(wire
		(pts
			(xy 85.09 226.06) (xy 93.98 226.06)
		)
		(stroke
			(width 0)
			(type default)
		)
	)
	(wire
		(pts
			(xy 259.08 256.54) (xy 259.08 257.81)
		)
		(stroke
			(width 0)
			(type default)
		)
	)
	(wire
		(pts
			(xy 270.51 217.17) (xy 270.51 218.44)
		)
		(stroke
			(width 0)
			(type default)
		)
	)
	(wire
		(pts
			(xy 339.09 71.12) (xy 339.09 69.85)
		)
		(stroke
			(width 0)
			(type default)
		)
	)
	(wire
		(pts
			(xy 60.96 194.31) (xy 60.96 199.39)
		)
		(stroke
			(width 0)
			(type default)
		)
	)
	(wire
		(pts
			(xy 288.29 203.2) (xy 289.56 203.2)
		)
		(stroke
			(width 0)
			(type default)
		)
	)
	(wire
		(pts
			(xy 309.88 86.36) (xy 314.96 86.36)
		)
		(stroke
			(width 0)
			(type default)
		)
	)
	(wire
		(pts
			(xy 73.66 204.47) (xy 83.82 204.47)
		)
		(stroke
			(width 0)
			(type default)
		)
	)
	(wire
		(pts
			(xy 132.08 234.95) (xy 120.65 234.95)
		)
		(stroke
			(width 0)
			(type default)
		)
	)
	(wire
		(pts
			(xy 316.23 218.44) (xy 318.77 218.44)
		)
		(stroke
			(width 0)
			(type default)
		)
	)
	(wire
		(pts
			(xy 322.58 82.55) (xy 326.39 82.55)
		)
		(stroke
			(width 0)
			(type default)
		)
	)
	(wire
		(pts
			(xy 299.72 69.85) (xy 321.31 69.85)
		)
		(stroke
			(width 0)
			(type default)
		)
	)
	(wire
		(pts
			(xy 69.85 182.88) (xy 76.2 182.88)
		)
		(stroke
			(width 0)
			(type default)
		)
	)
	(wire
		(pts
			(xy 266.7 167.64) (xy 288.29 167.64)
		)
		(stroke
			(width 0)
			(type default)
		)
	)
	(wire
		(pts
			(xy 247.65 217.17) (xy 247.65 218.44)
		)
		(stroke
			(width 0)
			(type default)
		)
	)
	(wire
		(pts
			(xy 247.65 250.19) (xy 259.08 250.19)
		)
		(stroke
			(width 0)
			(type default)
		)
	)
	(wire
		(pts
			(xy 266.7 167.64) (xy 266.7 170.18)
		)
		(stroke
			(width 0)
			(type default)
		)
	)
	(wire
		(pts
			(xy 106.68 77.47) (xy 96.52 77.47)
		)
		(stroke
			(width 0)
			(type default)
		)
	)
	(wire
		(pts
			(xy 212.09 63.5) (xy 212.09 67.31)
		)
		(stroke
			(width 0)
			(type default)
		)
	)
	(wire
		(pts
			(xy 284.48 213.36) (xy 284.48 210.82)
		)
		(stroke
			(width 0)
			(type default)
		)
	)
	(wire
		(pts
			(xy 184.15 172.72) (xy 194.31 172.72)
		)
		(stroke
			(width 0)
			(type default)
		)
	)
	(wire
		(pts
			(xy 259.08 210.82) (xy 270.51 210.82)
		)
		(stroke
			(width 0)
			(type default)
		)
	)
	(wire
		(pts
			(xy 118.11 24.13) (xy 118.11 27.94)
		)
		(stroke
			(width 0)
			(type default)
		)
	)
	(wire
		(pts
			(xy 318.77 210.82) (xy 318.77 213.36)
		)
		(stroke
			(width 0)
			(type default)
		)
	)
	(polyline
		(pts
			(xy 299.72 146.05) (xy 300.99 146.05)
		)
		(stroke
			(width 0)
			(type default)
		)
	)
	(wire
		(pts
			(xy 151.13 242.57) (xy 151.13 243.84)
		)
		(stroke
			(width 0)
			(type default)
		)
	)
	(wire
		(pts
			(xy 261.62 92.71) (xy 264.16 92.71)
		)
		(stroke
			(width 0)
			(type default)
		)
	)
	(wire
		(pts
			(xy 88.9 199.39) (xy 119.38 199.39)
		)
		(stroke
			(width 0)
			(type default)
		)
	)
	(wire
		(pts
			(xy 270.51 250.19) (xy 288.29 250.19)
		)
		(stroke
			(width 0)
			(type default)
		)
	)
	(wire
		(pts
			(xy 266.7 175.26) (xy 266.7 176.53)
		)
		(stroke
			(width 0)
			(type default)
		)
	)
	(wire
		(pts
			(xy 191.77 175.26) (xy 194.31 175.26)
		)
		(stroke
			(width 0)
			(type default)
		)
	)
	(wire
		(pts
			(xy 110.49 134.62) (xy 96.52 134.62)
		)
		(stroke
			(width 0)
			(type default)
		)
	)
	(polyline
		(pts
			(xy 224.79 12.7) (xy 224.79 146.05)
		)
		(stroke
			(width 0)
			(type default)
		)
	)
	(wire
		(pts
			(xy 120.65 237.49) (xy 162.56 237.49)
		)
		(stroke
			(width 0)
			(type default)
		)
	)
	(wire
		(pts
			(xy 299.72 93.98) (xy 322.58 93.98)
		)
		(stroke
			(width 0)
			(type default)
		)
	)
	(label "SDI_D12"
		(at 106.68 41.91 180)
		(effects
			(font
				(size 1.27 1.27)
			)
			(justify right bottom)
		)
	)
	(label "SDI_PCLK"
		(at 132.08 226.06 180)
		(effects
			(font
				(size 1.27 1.27)
			)
			(justify right bottom)
		)
	)
	(label "SDI_STAT0"
		(at 132.08 229.87 180)
		(effects
			(font
				(size 1.27 1.27)
			)
			(justify right bottom)
		)
	)
	(label "SDI_D19"
		(at 106.68 57.15 180)
		(effects
			(font
				(size 1.27 1.27)
			)
			(justify right bottom)
		)
	)
	(label "TIM_861"
		(at 167.64 203.2 180)
		(effects
			(font
				(size 1.27 1.27)
			)
			(justify right bottom)
		)
	)
	(label "SDI_D5"
		(at 85.09 238.76 0)
		(effects
			(font
				(size 1.27 1.27)
			)
			(justify left bottom)
		)
	)
	(label "SCLK_TCK"
		(at 110.49 121.92 180)
		(effects
			(font
				(size 1.27 1.27)
			)
			(justify right bottom)
		)
	)
	(label "RESET_TRST"
		(at 110.49 109.22 180)
		(effects
			(font
				(size 1.27 1.27)
			)
			(justify right bottom)
		)
	)
	(label "SDI_D14"
		(at 85.09 261.62 0)
		(effects
			(font
				(size 1.27 1.27)
			)
			(justify left bottom)
		)
	)
	(label "SDI_D18"
		(at 106.68 62.23 180)
		(effects
			(font
				(size 1.27 1.27)
			)
			(justify right bottom)
		)
	)
	(label "~{RC_BYP}"
		(at 167.64 185.42 180)
		(effects
			(font
				(size 1.27 1.27)
			)
			(justify right bottom)
		)
	)
	(label "SDI_STAT2"
		(at 106.68 74.93 180)
		(effects
			(font
				(size 1.27 1.27)
			)
			(justify right bottom)
		)
	)
	(label "SCLK_TCK"
		(at 167.64 190.5 180)
		(effects
			(font
				(size 1.27 1.27)
			)
			(justify right bottom)
		)
	)
	(label "SDI_D16"
		(at 106.68 77.47 180)
		(effects
			(font
				(size 1.27 1.27)
			)
			(justify right bottom)
		)
	)
	(label "SDIN_TDI"
		(at 106.68 26.67 180)
		(effects
			(font
				(size 1.27 1.27)
			)
			(justify right bottom)
		)
	)
	(label "SDI_D15"
		(at 106.68 44.45 180)
		(effects
			(font
				(size 1.27 1.27)
			)
			(justify right bottom)
		)
	)
	(label "~{SMPTE_BYPASS}"
		(at 195.58 83.82 180)
		(effects
			(font
				(size 1.27 1.27)
			)
			(justify right bottom)
		)
	)
	(label "SDI_D7"
		(at 85.09 243.84 0)
		(effects
			(font
				(size 1.27 1.27)
			)
			(justify left bottom)
		)
	)
	(label "SDI_N2"
		(at 82.55 204.47 180)
		(effects
			(font
				(size 1.27 1.27)
			)
			(justify right bottom)
		)
	)
	(label "SW_EN"
		(at 167.64 200.66 180)
		(effects
			(font
				(size 1.27 1.27)
			)
			(justify right bottom)
		)
	)
	(label "DVB_ASI"
		(at 167.64 167.64 180)
		(effects
			(font
				(size 1.27 1.27)
			)
			(justify right bottom)
		)
	)
	(label "RESET_TRST"
		(at 167.64 187.96 180)
		(effects
			(font
				(size 1.27 1.27)
			)
			(justify right bottom)
		)
	)
	(label "SDI_N"
		(at 111.76 201.93 0)
		(effects
			(font
				(size 1.27 1.27)
			)
			(justify left bottom)
		)
	)
	(label "SDI_D17"
		(at 85.09 269.24 0)
		(effects
			(font
				(size 1.27 1.27)
			)
			(justify left bottom)
		)
	)
	(label "SDO_EN{slash}DIS"
		(at 167.64 195.58 180)
		(effects
			(font
				(size 1.27 1.27)
			)
			(justify right bottom)
		)
	)
	(label "SDI_D3"
		(at 85.09 233.68 0)
		(effects
			(font
				(size 1.27 1.27)
			)
			(justify left bottom)
		)
	)
	(label "SDI_D3"
		(at 106.68 54.61 180)
		(effects
			(font
				(size 1.27 1.27)
			)
			(justify right bottom)
		)
	)
	(label "SDI_D4"
		(at 106.68 46.99 180)
		(effects
			(font
				(size 1.27 1.27)
			)
			(justify right bottom)
		)
	)
	(label "SDI_D17"
		(at 110.49 116.84 180)
		(effects
			(font
				(size 1.27 1.27)
			)
			(justify right bottom)
		)
	)
	(label "SDI_IN"
		(at 48.26 199.39 180)
		(effects
			(font
				(size 1.27 1.27)
			)
			(justify right bottom)
		)
	)
	(label "AGC_N"
		(at 111.76 193.04 0)
		(effects
			(font
				(size 1.27 1.27)
			)
			(justify left bottom)
		)
	)
	(label "SDI_OUT_P"
		(at 303.53 69.85 0)
		(effects
			(font
				(size 1.27 1.27)
			)
			(justify left bottom)
		)
	)
	(label "~{RC_BYP}"
		(at 195.58 96.52 180)
		(effects
			(font
				(size 1.27 1.27)
			)
			(justify right bottom)
		)
	)
	(label "~{SDO_DISABLE}"
		(at 110.49 132.08 180)
		(effects
			(font
				(size 1.27 1.27)
			)
			(justify right bottom)
		)
	)
	(label "~{SDO_DISABLE}"
		(at 247.65 87.63 0)
		(effects
			(font
				(size 1.27 1.27)
			)
			(justify left bottom)
		)
	)
	(label "SW_EN"
		(at 110.49 114.3 180)
		(effects
			(font
				(size 1.27 1.27)
			)
			(justify right bottom)
		)
	)
	(label "TIM_861"
		(at 106.68 34.29 180)
		(effects
			(font
				(size 1.27 1.27)
			)
			(justify right bottom)
		)
	)
	(label "SDI_OUT"
		(at 364.49 93.98 180)
		(effects
			(font
				(size 1.27 1.27)
			)
			(justify right bottom)
		)
	)
	(label "XTAL1"
		(at 83.82 179.07 180)
		(effects
			(font
				(size 1.27 1.27)
			)
			(justify right bottom)
		)
	)
	(label "SDI_STAT3"
		(at 132.08 237.49 180)
		(effects
			(font
				(size 1.27 1.27)
			)
			(justify right bottom)
		)
	)
	(label "~{CS_TMS}"
		(at 167.64 177.8 180)
		(effects
			(font
				(size 1.27 1.27)
			)
			(justify right bottom)
		)
	)
	(label "SDI_D13"
		(at 85.09 259.08 0)
		(effects
			(font
				(size 1.27 1.27)
			)
			(justify left bottom)
		)
	)
	(label "SDI_D5"
		(at 106.68 49.53 180)
		(effects
			(font
				(size 1.27 1.27)
			)
			(justify right bottom)
		)
	)
	(label "SDI_D9"
		(at 106.68 59.69 180)
		(effects
			(font
				(size 1.27 1.27)
			)
			(justify right bottom)
		)
	)
	(label "SDI_D4"
		(at 85.09 236.22 0)
		(effects
			(font
				(size 1.27 1.27)
			)
			(justify left bottom)
		)
	)
	(label "SDI_D14"
		(at 110.49 111.76 180)
		(effects
			(font
				(size 1.27 1.27)
			)
			(justify right bottom)
		)
	)
	(label "SDI_D10"
		(at 106.68 29.21 180)
		(effects
			(font
				(size 1.27 1.27)
			)
			(justify right bottom)
		)
	)
	(label "JTAG{slash}~{HOST}"
		(at 195.58 93.98 180)
		(effects
			(font
				(size 1.27 1.27)
			)
			(justify right bottom)
		)
	)
	(label "SDO_EN{slash}DIS"
		(at 110.49 127 180)
		(effects
			(font
				(size 1.27 1.27)
			)
			(justify right bottom)
		)
	)
	(label "SDI_D7"
		(at 106.68 36.83 180)
		(effects
			(font
				(size 1.27 1.27)
			)
			(justify right bottom)
		)
	)
	(label "STANDBY"
		(at 110.49 124.46 180)
		(effects
			(font
				(size 1.27 1.27)
			)
			(justify right bottom)
		)
	)
	(label "SDI_PCLK"
		(at 106.68 80.01 180)
		(effects
			(font
				(size 1.27 1.27)
			)
			(justify right bottom)
		)
	)
	(label "JTAG{slash}~{HOST}"
		(at 167.64 182.88 180)
		(effects
			(font
				(size 1.27 1.27)
			)
			(justify right bottom)
		)
	)
	(label "SDI_D18"
		(at 85.09 271.78 0)
		(effects
			(font
				(size 1.27 1.27)
			)
			(justify left bottom)
		)
	)
	(label "SDI_D8"
		(at 106.68 31.75 180)
		(effects
			(font
				(size 1.27 1.27)
			)
			(justify right bottom)
		)
	)
	(label "SDOUT_TDO"
		(at 167.64 205.74 180)
		(effects
			(font
				(size 1.27 1.27)
			)
			(justify right bottom)
		)
	)
	(label "IOPROC_EN{slash}~{DIS}"
		(at 167.64 180.34 180)
		(effects
			(font
				(size 1.27 1.27)
			)
			(justify right bottom)
		)
	)
	(label "SDIN_TDI"
		(at 167.64 193.04 180)
		(effects
			(font
				(size 1.27 1.27)
			)
			(justify right bottom)
		)
	)
	(label "20bit{slash}~{10bit}"
		(at 167.64 172.72 180)
		(effects
			(font
				(size 1.27 1.27)
			)
			(justify right bottom)
		)
	)
	(label "SDOUT_TDO"
		(at 110.49 129.54 180)
		(effects
			(font
				(size 1.27 1.27)
			)
			(justify right bottom)
		)
	)
	(label "SDO_P"
		(at 247.65 81.28 0)
		(effects
			(font
				(size 1.27 1.27)
			)
			(justify left bottom)
		)
	)
	(label "SDI_D16"
		(at 85.09 266.7 0)
		(effects
			(font
				(size 1.27 1.27)
			)
			(justify left bottom)
		)
	)
	(label "SDI_STAT4"
		(at 106.68 72.39 180)
		(effects
			(font
				(size 1.27 1.27)
			)
			(justify right bottom)
		)
	)
	(label "SDI_STAT0"
		(at 106.68 87.63 180)
		(effects
			(font
				(size 1.27 1.27)
			)
			(justify right bottom)
		)
	)
	(label "SDI_D0"
		(at 85.09 226.06 0)
		(effects
			(font
				(size 1.27 1.27)
			)
			(justify left bottom)
		)
	)
	(label "SDI_STAT1"
		(at 132.08 232.41 180)
		(effects
			(font
				(size 1.27 1.27)
			)
			(justify right bottom)
		)
	)
	(label "SDI_OUT_N"
		(at 313.69 93.98 180)
		(effects
			(font
				(size 1.27 1.27)
			)
			(justify right bottom)
		)
	)
	(label "SDI_D12"
		(at 85.09 256.54 0)
		(effects
			(font
				(size 1.27 1.27)
			)
			(justify left bottom)
		)
	)
	(label "SDI_D2"
		(at 106.68 52.07 180)
		(effects
			(font
				(size 1.27 1.27)
			)
			(justify right bottom)
		)
	)
	(label "SDI_D11"
		(at 85.09 254 0)
		(effects
			(font
				(size 1.27 1.27)
			)
			(justify left bottom)
		)
	)
	(label "STANDBY"
		(at 167.64 198.12 180)
		(effects
			(font
				(size 1.27 1.27)
			)
			(justify right bottom)
		)
	)
	(label "AGC_P"
		(at 111.76 190.5 0)
		(effects
			(font
				(size 1.27 1.27)
			)
			(justify left bottom)
		)
	)
	(label "~{CS_TMS}"
		(at 110.49 119.38 180)
		(effects
			(font
				(size 1.27 1.27)
			)
			(justify right bottom)
		)
	)
	(label "SDI_STAT5"
		(at 110.49 134.62 180)
		(effects
			(font
				(size 1.27 1.27)
			)
			(justify right bottom)
		)
	)
	(label "SDI_D8"
		(at 85.09 246.38 0)
		(effects
			(font
				(size 1.27 1.27)
			)
			(justify left bottom)
		)
	)
	(label "SDI_D11"
		(at 106.68 39.37 180)
		(effects
			(font
				(size 1.27 1.27)
			)
			(justify right bottom)
		)
	)
	(label "IOPROC_EN{slash}~{DIS}"
		(at 196.85 78.74 180)
		(effects
			(font
				(size 1.27 1.27)
			)
			(justify right bottom)
		)
	)
	(label "XTAL2"
		(at 83.82 176.53 180)
		(effects
			(font
				(size 1.27 1.27)
			)
			(justify right bottom)
		)
	)
	(label "SDI_P"
		(at 111.76 199.39 0)
		(effects
			(font
				(size 1.27 1.27)
			)
			(justify left bottom)
		)
	)
	(label "SDO_N"
		(at 247.65 83.82 0)
		(effects
			(font
				(size 1.27 1.27)
			)
			(justify left bottom)
		)
	)
	(label "XTAL2"
		(at 109.22 180.34 0)
		(effects
			(font
				(size 1.27 1.27)
			)
			(justify left bottom)
		)
	)
	(label "DVB_ASI"
		(at 196.85 73.66 180)
		(effects
			(font
				(size 1.27 1.27)
			)
			(justify right bottom)
		)
	)
	(label "SDI_STAT1"
		(at 106.68 82.55 180)
		(effects
			(font
				(size 1.27 1.27)
			)
			(justify right bottom)
		)
	)
	(label "SDI_D0"
		(at 106.68 67.31 180)
		(effects
			(font
				(size 1.27 1.27)
			)
			(justify right bottom)
		)
	)
	(label "SDI_D6"
		(at 106.68 85.09 180)
		(effects
			(font
				(size 1.27 1.27)
			)
			(justify right bottom)
		)
	)
	(label "SDO_P"
		(at 130.81 269.24 180)
		(effects
			(font
				(size 1.27 1.27)
			)
			(justify right bottom)
		)
	)
	(label "SDI_OUT_F2"
		(at 337.82 93.98 0)
		(effects
			(font
				(size 1.27 1.27)
			)
			(justify left bottom)
		)
	)
	(label "SDI_D15"
		(at 85.09 264.16 0)
		(effects
			(font
				(size 1.27 1.27)
			)
			(justify left bottom)
		)
	)
	(label "SDI_D13"
		(at 106.68 64.77 180)
		(effects
			(font
				(size 1.27 1.27)
			)
			(justify right bottom)
		)
	)
	(label "~{SMPTE_BYPASS}"
		(at 167.64 170.18 180)
		(effects
			(font
				(size 1.27 1.27)
			)
			(justify right bottom)
		)
	)
	(label "SDI_D2"
		(at 85.09 231.14 0)
		(effects
			(font
				(size 1.27 1.27)
			)
			(justify left bottom)
		)
	)
	(label "SDI_STAT3"
		(at 106.68 90.17 180)
		(effects
			(font
				(size 1.27 1.27)
			)
			(justify right bottom)
		)
	)
	(label "SDI_STAT5"
		(at 132.08 242.57 180)
		(effects
			(font
				(size 1.27 1.27)
			)
			(justify right bottom)
		)
	)
	(label "SDI_D1"
		(at 106.68 69.85 180)
		(effects
			(font
				(size 1.27 1.27)
			)
			(justify right bottom)
		)
	)
	(label "SDI_D9"
		(at 85.09 248.92 0)
		(effects
			(font
				(size 1.27 1.27)
			)
			(justify left bottom)
		)
	)
	(label "SDI_STAT2"
		(at 132.08 234.95 180)
		(effects
			(font
				(size 1.27 1.27)
			)
			(justify right bottom)
		)
	)
	(label "SDO_N"
		(at 130.81 271.78 180)
		(effects
			(font
				(size 1.27 1.27)
			)
			(justify right bottom)
		)
	)
	(label "SDI_D10"
		(at 85.09 251.46 0)
		(effects
			(font
				(size 1.27 1.27)
			)
			(justify left bottom)
		)
	)
	(label "AUDIO_EN{slash}~{DIS}"
		(at 167.64 175.26 180)
		(effects
			(font
				(size 1.27 1.27)
			)
			(justify right bottom)
		)
	)
	(label "SDI_D6"
		(at 85.09 241.3 0)
		(effects
			(font
				(size 1.27 1.27)
			)
			(justify left bottom)
		)
	)
	(label "XTAL1"
		(at 109.22 177.8 0)
		(effects
			(font
				(size 1.27 1.27)
			)
			(justify left bottom)
		)
	)
	(label "SDI_IN_F"
		(at 82.55 199.39 180)
		(effects
			(font
				(size 1.27 1.27)
			)
			(justify right bottom)
		)
	)
	(label "SDI_D1"
		(at 85.09 228.6 0)
		(effects
			(font
				(size 1.27 1.27)
			)
			(justify left bottom)
		)
	)
	(label "SDI_STAT4"
		(at 132.08 240.03 180)
		(effects
			(font
				(size 1.27 1.27)
			)
			(justify right bottom)
		)
	)
	(label "SDI_D19"
		(at 85.09 274.32 0)
		(effects
			(font
				(size 1.27 1.27)
			)
			(justify left bottom)
		)
	)
	(global_label "AUDIO_OUT_CH7_8"
		(shape input)
		(at 120.65 264.16 0)
		(fields_autoplaced yes)
		(effects
			(font
				(size 1.27 1.27)
			)
			(justify left)
		)
		(property "Intersheetrefs" "${INTERSHEET_REFS}"
			(at 140.2383 264.0806 0)
			(effects
				(font
					(size 1.27 1.27)
				)
				(justify left)
				(hide yes)
			)
		)
	)
	(global_label "AUDIO_OUT_CH1_2"
		(shape input)
		(at 120.65 256.54 0)
		(fields_autoplaced yes)
		(effects
			(font
				(size 1.27 1.27)
			)
			(justify left)
		)
		(property "Intersheetrefs" "${INTERSHEET_REFS}"
			(at 140.2383 256.4606 0)
			(effects
				(font
					(size 1.27 1.27)
				)
				(justify left)
				(hide yes)
			)
		)
	)
	(global_label "AUDIO_OUT_CH3_4"
		(shape input)
		(at 120.65 259.08 0)
		(fields_autoplaced yes)
		(effects
			(font
				(size 1.27 1.27)
			)
			(justify left)
		)
		(property "Intersheetrefs" "${INTERSHEET_REFS}"
			(at 140.2383 259.0006 0)
			(effects
				(font
					(size 1.27 1.27)
				)
				(justify left)
				(hide yes)
			)
		)
	)
	(global_label "GPIO0"
		(shape input)
		(at 196.85 66.04 0)
		(fields_autoplaced yes)
		(effects
			(font
				(size 1.27 1.27)
			)
			(justify left)
		)
		(property "Intersheetrefs" "${INTERSHEET_REFS}"
			(at 204.9479 65.9606 0)
			(effects
				(font
					(size 1.27 1.27)
				)
				(justify left)
				(hide yes)
			)
		)
	)
	(global_label "AUDIO_OUT_CH5_6"
		(shape input)
		(at 120.65 261.62 0)
		(fields_autoplaced yes)
		(effects
			(font
				(size 1.27 1.27)
			)
			(justify left)
		)
		(property "Intersheetrefs" "${INTERSHEET_REFS}"
			(at 140.2383 261.5406 0)
			(effects
				(font
					(size 1.27 1.27)
				)
				(justify left)
				(hide yes)
			)
		)
	)
	(global_label "GPIO1"
		(shape input)
		(at 196.85 71.12 0)
		(fields_autoplaced yes)
		(effects
			(font
				(size 1.27 1.27)
			)
			(justify left)
		)
		(property "Intersheetrefs" "${INTERSHEET_REFS}"
			(at 204.9479 71.0406 0)
			(effects
				(font
					(size 1.27 1.27)
				)
				(justify left)
				(hide yes)
			)
		)
	)
	(global_label "FCC2_SCL2"
		(shape input)
		(at 196.85 81.28 0)
		(fields_autoplaced yes)
		(effects
			(font
				(size 1.27 1.27)
			)
			(justify left)
		)
		(property "Intersheetrefs" "${INTERSHEET_REFS}"
			(at 209.786 81.2006 0)
			(effects
				(font
					(size 1.27 1.27)
				)
				(justify left)
				(hide yes)
			)
		)
	)
	(global_label "AUDIO_MCLK"
		(shape input)
		(at 120.65 251.46 0)
		(fields_autoplaced yes)
		(effects
			(font
				(size 1.27 1.27)
			)
			(justify left)
		)
		(property "Intersheetrefs" "${INTERSHEET_REFS}"
			(at 134.6745 251.3806 0)
			(effects
				(font
					(size 1.27 1.27)
				)
				(justify left)
				(hide yes)
			)
		)
	)
	(global_label "AUDIO_WCLK"
		(shape input)
		(at 120.65 246.38 0)
		(fields_autoplaced yes)
		(effects
			(font
				(size 1.27 1.27)
			)
			(justify left)
		)
		(property "Intersheetrefs" "${INTERSHEET_REFS}"
			(at 134.6745 246.3006 0)
			(effects
				(font
					(size 1.27 1.27)
				)
				(justify left)
				(hide yes)
			)
		)
	)
	(global_label "GPIO3"
		(shape input)
		(at 196.85 86.36 0)
		(fields_autoplaced yes)
		(effects
			(font
				(size 1.27 1.27)
			)
			(justify left)
		)
		(property "Intersheetrefs" "${INTERSHEET_REFS}"
			(at 204.9479 86.2806 0)
			(effects
				(font
					(size 1.27 1.27)
				)
				(justify left)
				(hide yes)
			)
		)
	)
	(global_label "TXD"
		(shape input)
		(at 196.85 88.9 0)
		(fields_autoplaced yes)
		(effects
			(font
				(size 1.27 1.27)
			)
			(justify left)
		)
		(property "Intersheetrefs" "${INTERSHEET_REFS}"
			(at 202.7102 88.8206 0)
			(effects
				(font
					(size 1.27 1.27)
				)
				(justify left)
				(hide yes)
			)
		)
	)
	(global_label "AUDIO_ACLK"
		(shape input)
		(at 120.65 248.92 0)
		(fields_autoplaced yes)
		(effects
			(font
				(size 1.27 1.27)
			)
			(justify left)
		)
		(property "Intersheetrefs" "${INTERSHEET_REFS}"
			(at 134.3117 248.8406 0)
			(effects
				(font
					(size 1.27 1.27)
				)
				(justify left)
				(hide yes)
			)
		)
	)
	(global_label "GPIO2"
		(shape input)
		(at 196.85 68.58 0)
		(fields_autoplaced yes)
		(effects
			(font
				(size 1.27 1.27)
			)
			(justify left)
		)
		(property "Intersheetrefs" "${INTERSHEET_REFS}"
			(at 204.9479 68.5006 0)
			(effects
				(font
					(size 1.27 1.27)
				)
				(justify left)
				(hide yes)
			)
		)
	)
	(global_label "RXD"
		(shape input)
		(at 196.85 91.44 0)
		(fields_autoplaced yes)
		(effects
			(font
				(size 1.27 1.27)
			)
			(justify left)
		)
		(property "Intersheetrefs" "${INTERSHEET_REFS}"
			(at 203.0126 91.3606 0)
			(effects
				(font
					(size 1.27 1.27)
				)
				(justify left)
				(hide yes)
			)
		)
	)
	(global_label "DIP1"
		(shape input)
		(at 196.85 76.2 0)
		(fields_autoplaced yes)
		(effects
			(font
				(size 1.27 1.27)
			)
			(justify left)
		)
		(property "Intersheetrefs" "${INTERSHEET_REFS}"
			(at 203.6174 76.1206 0)
			(effects
				(font
					(size 1.27 1.27)
				)
				(justify left)
				(hide yes)
			)
		)
	)
	(symbol
		(lib_id "antmicroInterfaceControllers:GS2971A")
		(at 289.56 203.2 0)
		(unit 3)
		(exclude_from_sim no)
		(in_bom yes)
		(on_board yes)
		(dnp no)
		(fields_autoplaced yes)
		(property "Reference" "U15"
			(at 302.895 195.58 0)
			(effects
				(font
					(size 1.27 1.27)
					(thickness 0.15)
				)
			)
		)
		(property "Value" "GS2971A"
			(at 302.895 198.12 0)
			(effects
				(font
					(size 1.27 1.27)
					(thickness 0.15)
				)
			)
		)
		(property "Footprint" "antmicro-footprints:BGA-100_11x11mm_Layout10x10_P1mm"
			(at 345.44 210.82 0)
			(effects
				(font
					(size 1.27 1.27)
					(thickness 0.15)
				)
				(justify left bottom)
				(hide yes)
			)
		)
		(property "Datasheet" "https://semtech.my.salesforce.com/sfc/p/#E0000000JelG/a/44000000MD3i/kpmMkrmUWgHlbCOwdLzVohMm1SDPoVH85guEGK.KXTc"
			(at 345.44 213.36 0)
			(effects
				(font
					(size 1.27 1.27)
					(thickness 0.15)
				)
				(justify left bottom)
				(hide yes)
			)
		)
		(property "Description" "SDI receiver"
			(at 289.56 203.2 0)
			(effects
				(font
					(size 1.27 1.27)
				)
				(hide yes)
			)
		)
		(property "MPN" "GS2971A"
			(at 345.44 215.9 0)
			(effects
				(font
					(size 1.27 1.27)
					(thickness 0.15)
				)
				(justify left bottom)
				(hide yes)
			)
		)
		(property "Manufacturer" "Semtech"
			(at 345.44 218.44 0)
			(effects
				(font
					(size 1.27 1.27)
					(thickness 0.15)
				)
				(justify left bottom)
				(hide yes)
			)
		)
		(property "Author" "Antmicro"
			(at 345.44 220.98 0)
			(effects
				(font
					(size 1.27 1.27)
					(thickness 0.15)
				)
				(justify left bottom)
				(hide yes)
			)
		)
		(property "License" "Apache-2.0"
			(at 345.44 223.52 0)
			(effects
				(font
					(size 1.27 1.27)
					(thickness 0.15)
				)
				(justify left bottom)
				(hide yes)
			)
		)
		(pin "A10"
		)
		(pin "A5"
		)
		(pin "A6"
		)
		(pin "A8"
		)
		(pin "A9"
		)
		(pin "B10"
		)
		(pin "B5"
		)
		(pin "B6"
		)
		(pin "B8"
		)
		(pin "B9"
		)
		(pin "C10"
		)
		(pin "C5"
		)
		(pin "C6"
		)
		(pin "C8"
		)
		(pin "C9"
		)
		(pin "E10"
		)
		(pin "E9"
		)
		(pin "F10"
		)
		(pin "F9"
		)
		(pin "H10"
		)
		(pin "H4"
		)
		(pin "H9"
		)
		(pin "J1"
		)
		(pin "J10"
		)
		(pin "J3"
		)
		(pin "J4"
		)
		(pin "J5"
		)
		(pin "J8"
		)
		(pin "J9"
		)
		(pin "K1"
		)
		(pin "K10"
		)
		(pin "K3"
		)
		(pin "K4"
		)
		(pin "K5"
		)
		(pin "K8"
		)
		(pin "K9"
		)
		(pin "A1"
		)
		(pin "A2"
		)
		(pin "A3"
		)
		(pin "B3"
		)
		(pin "C1"
		)
		(pin "C7"
		)
		(pin "D1"
		)
		(pin "D7"
		)
		(pin "D8"
		)
		(pin "E7"
		)
		(pin "E8"
		)
		(pin "F1"
		)
		(pin "F2"
		)
		(pin "F7"
		)
		(pin "F8"
		)
		(pin "G1"
		)
		(pin "G3"
		)
		(pin "G7"
		)
		(pin "G8"
		)
		(pin "H3"
		)
		(pin "H5"
		)
		(pin "H6"
		)
		(pin "H7"
		)
		(pin "H8"
		)
		(pin "J2"
		)
		(pin "J6"
		)
		(pin "K2"
		)
		(pin "K6"
		)
		(pin "A4"
		)
		(pin "A7"
		)
		(pin "B1"
		)
		(pin "B2"
		)
		(pin "B4"
		)
		(pin "B7"
		)
		(pin "C2"
		)
		(pin "C3"
		)
		(pin "C4"
		)
		(pin "D10"
		)
		(pin "D2"
		)
		(pin "D3"
		)
		(pin "D4"
		)
		(pin "D5"
		)
		(pin "D6"
		)
		(pin "D9"
		)
		(pin "E1"
		)
		(pin "E2"
		)
		(pin "E3"
		)
		(pin "E4"
		)
		(pin "E5"
		)
		(pin "E6"
		)
		(pin "F3"
		)
		(pin "F4"
		)
		(pin "F5"
		)
		(pin "F6"
		)
		(pin "G10"
		)
		(pin "G2"
		)
		(pin "G4"
		)
		(pin "G5"
		)
		(pin "G6"
		)
		(pin "G9"
		)
		(pin "H1"
		)
		(pin "H2"
		)
		(pin "J7"
		)
		(pin "K7"
		)
		(instances
			(project "sdi-mipi-video-converter"
				(path ""
					(reference "U15")
					(unit 3)
				)
			)
		)
	)
	(symbol
		(lib_id "antmicropower:GND")
		(at 162.56 259.08 0)
		(unit 1)
		(exclude_from_sim no)
		(in_bom yes)
		(on_board yes)
		(dnp no)
		(property "Reference" "#PWR0248"
			(at 171.45 261.62 0)
			(effects
				(font
					(size 1.27 1.27)
					(thickness 0.15)
				)
				(justify left bottom)
				(hide yes)
			)
		)
		(property "Value" "GND"
			(at 164.465 262.89 0)
			(effects
				(font
					(size 1.27 1.27)
					(thickness 0.15)
				)
				(justify right)
			)
		)
		(property "Footprint" ""
			(at 171.45 266.7 0)
			(effects
				(font
					(size 1.27 1.27)
					(thickness 0.15)
				)
				(justify left bottom)
				(hide yes)
			)
		)
		(property "Datasheet" ""
			(at 171.45 271.78 0)
			(effects
				(font
					(size 1.27 1.27)
					(thickness 0.15)
				)
				(justify left bottom)
				(hide yes)
			)
		)
		(property "Description" ""
			(at 162.56 259.08 0)
			(effects
				(font
					(size 1.27 1.27)
				)
				(hide yes)
			)
		)
		(property "Author" "Antmicro"
			(at 171.45 266.7 0)
			(effects
				(font
					(size 1.27 1.27)
					(thickness 0.15)
				)
				(justify left bottom)
				(hide yes)
			)
		)
		(property "License" "Apache-2.0"
			(at 171.45 269.24 0)
			(effects
				(font
					(size 1.27 1.27)
					(thickness 0.15)
				)
				(justify left bottom)
				(hide yes)
			)
		)
		(pin "1"
		)
		(instances
			(project "sdi-mipi-video-converter"
				(path ""
					(reference "#PWR0248")
					(unit 1)
				)
			)
		)
	)
	(symbol
		(lib_id "antmicroCapacitors0402:C_100n_0402")
		(at 247.65 191.77 90)
		(unit 1)
		(exclude_from_sim no)
		(in_bom yes)
		(on_board yes)
		(dnp no)
		(fields_autoplaced yes)
		(property "Reference" "C61"
			(at 250.19 187.9535 90)
			(effects
				(font
					(size 1.27 1.27)
					(thickness 0.15)
				)
				(justify right)
			)
		)
		(property "Value" "C_100n_0402"
			(at 257.81 171.45 0)
			(effects
				(font
					(size 1.27 1.27)
					(thickness 0.15)
				)
				(justify left bottom)
				(hide yes)
			)
		)
		(property "Footprint" "antmicro-footprints:C_0402_1005Metric"
			(at 260.35 171.45 0)
			(effects
				(font
					(size 1.27 1.27)
					(thickness 0.15)
				)
				(justify left bottom)
				(hide yes)
			)
		)
		(property "Datasheet" "https://www.murata.com/products/productdetail?partno=GRM155R61H104KE14%23"
			(at 262.89 171.45 0)
			(effects
				(font
					(size 1.27 1.27)
					(thickness 0.15)
				)
				(justify left bottom)
				(hide yes)
			)
		)
		(property "Description" "SMD Multilayer Ceramic Capacitor, 0.1 µF, 50 V, 0402 [1005 Metric], ± 10%, X5R, GRM Series"
			(at 247.65 191.77 0)
			(effects
				(font
					(size 1.27 1.27)
				)
				(hide yes)
			)
		)
		(property "Manufacturer" "Murata"
			(at 267.97 171.45 0)
			(effects
				(font
					(size 1.27 1.27)
					(thickness 0.15)
				)
				(justify left bottom)
				(hide yes)
			)
		)
		(property "MPN" "GRM155R61H104KE14D"
			(at 265.43 171.45 0)
			(effects
				(font
					(size 1.27 1.27)
					(thickness 0.15)
				)
				(justify left bottom)
				(hide yes)
			)
		)
		(property "Val" "100n"
			(at 250.19 190.4935 90)
			(effects
				(font
					(size 1.27 1.27)
					(thickness 0.15)
				)
				(justify right)
			)
		)
		(property "License" "Apache-2.0"
			(at 270.51 171.45 0)
			(effects
				(font
					(size 1.27 1.27)
					(thickness 0.15)
				)
				(justify left bottom)
				(hide yes)
			)
		)
		(property "Author" "Antmicro"
			(at 273.05 171.45 0)
			(effects
				(font
					(size 1.27 1.27)
					(thickness 0.15)
				)
				(justify left bottom)
				(hide yes)
			)
		)
		(property "Voltage" "50V"
			(at 275.59 171.45 0)
			(effects
				(font
					(size 1.27 1.27)
				)
				(justify left bottom)
				(hide yes)
			)
		)
		(property "Dielectric" "X5R"
			(at 278.13 171.45 0)
			(effects
				(font
					(size 1.27 1.27)
				)
				(justify left bottom)
				(hide yes)
			)
		)
		(pin "1"
		)
		(pin "2"
		)
		(instances
			(project "sdi-mipi-video-converter"
				(path ""
					(reference "C61")
					(unit 1)
				)
			)
		)
	)
	(symbol
		(lib_id "antmicroResistors0402:R_105R_0402")
		(at 266.7 161.29 90)
		(mirror x)
		(unit 1)
		(exclude_from_sim no)
		(in_bom yes)
		(on_board yes)
		(dnp no)
		(fields_autoplaced yes)
		(property "Reference" "R56"
			(at 269.24 162.5599 90)
			(effects
				(font
					(size 1.27 1.27)
					(thickness 0.15)
				)
				(justify right)
			)
		)
		(property "Value" "R_105R_0402"
			(at 279.4 181.61 0)
			(effects
				(font
					(size 1.27 1.27)
					(thickness 0.15)
				)
				(justify left bottom)
				(hide yes)
			)
		)
		(property "Footprint" "antmicro-footprints:R_0402_1005Metric"
			(at 281.94 181.61 0)
			(effects
				(font
					(size 1.27 1.27)
					(thickness 0.15)
				)
				(justify left bottom)
				(hide yes)
			)
		)
		(property "Datasheet" "https://www.bourns.com/docs/product-datasheets/cr.pdf"
			(at 284.48 181.61 0)
			(effects
				(font
					(size 1.27 1.27)
					(thickness 0.15)
				)
				(justify left bottom)
				(hide yes)
			)
		)
		(property "Description" "SMD Chip Resistor, 105 ohm, ± 1%, 62.5 mW, 0402 [1005 Metric], Thick Film, General Purpose"
			(at 266.7 161.29 0)
			(effects
				(font
					(size 1.27 1.27)
				)
				(hide yes)
			)
		)
		(property "Manufacturer" "Bourns"
			(at 289.56 181.61 0)
			(effects
				(font
					(size 1.27 1.27)
					(thickness 0.15)
				)
				(justify left bottom)
				(hide yes)
			)
		)
		(property "MPN" "CR0402-FX-1050GLF"
			(at 287.02 181.61 0)
			(effects
				(font
					(size 1.27 1.27)
					(thickness 0.15)
				)
				(justify left bottom)
				(hide yes)
			)
		)
		(property "Val" "105R"
			(at 269.24 165.0999 90)
			(effects
				(font
					(size 1.27 1.27)
					(thickness 0.15)
				)
				(justify right)
			)
		)
		(property "License" "Apache-2.0"
			(at 292.1 181.61 0)
			(effects
				(font
					(size 1.27 1.27)
					(thickness 0.15)
				)
				(justify left bottom)
				(hide yes)
			)
		)
		(property "Author" "Antmicro"
			(at 294.64 181.61 0)
			(effects
				(font
					(size 1.27 1.27)
					(thickness 0.15)
				)
				(justify left bottom)
				(hide yes)
			)
		)
		(property "Tolerance" "1%"
			(at 276.86 181.61 0)
			(effects
				(font
					(size 1.27 1.27)
				)
				(justify left bottom)
				(hide yes)
			)
		)
		(pin "1"
		)
		(pin "2"
		)
		(instances
			(project "sdi-mipi-video-converter"
				(path ""
					(reference "R56")
					(unit 1)
				)
			)
		)
	)
	(symbol
		(lib_id "antmicroTestPoints:TP_0.75mm_SMD")
		(at 168.91 182.88 0)
		(unit 1)
		(exclude_from_sim no)
		(in_bom yes)
		(on_board yes)
		(dnp no)
		(fields_autoplaced yes)
		(property "Reference" "TP34"
			(at 173.99 182.8799 0)
			(effects
				(font
					(size 1.27 1.27)
					(thickness 0.15)
				)
				(justify left)
			)
		)
		(property "Value" "TP_0.75mm_SMD"
			(at 186.69 190.5 0)
			(effects
				(font
					(size 1.27 1.27)
					(thickness 0.15)
				)
				(justify left bottom)
				(hide yes)
			)
		)
		(property "Footprint" "antmicro-footprints:TP_SMD_0.75mm"
			(at 186.69 193.04 0)
			(effects
				(font
					(size 1.27 1.27)
					(thickness 0.15)
				)
				(justify left bottom)
				(hide yes)
			)
		)
		(property "Datasheet" ""
			(at 186.69 195.58 0)
			(effects
				(font
					(size 1.27 1.27)
					(thickness 0.15)
				)
				(justify left bottom)
				(hide yes)
			)
		)
		(property "Description" "SMT test point"
			(at 168.91 182.88 0)
			(effects
				(font
					(size 1.27 1.27)
				)
				(hide yes)
			)
		)
		(property "MPN" ""
			(at 186.69 198.12 0)
			(effects
				(font
					(size 1.27 1.27)
					(thickness 0.15)
				)
				(justify left bottom)
				(hide yes)
			)
		)
		(property "Manufacturer" ""
			(at 186.69 200.66 0)
			(effects
				(font
					(size 1.27 1.27)
					(thickness 0.15)
				)
				(justify left bottom)
				(hide yes)
			)
		)
		(property "Author" "Antmicro"
			(at 186.69 203.2 0)
			(effects
				(font
					(size 1.27 1.27)
					(thickness 0.15)
				)
				(justify left bottom)
				(hide yes)
			)
		)
		(property "License" "Apache-2.0"
			(at 186.69 205.74 0)
			(effects
				(font
					(size 1.27 1.27)
					(thickness 0.15)
				)
				(justify left bottom)
				(hide yes)
			)
		)
		(pin "1"
		)
		(instances
			(project "sdi-mipi-video-converter"
				(path ""
					(reference "TP34")
					(unit 1)
				)
			)
		)
	)
	(symbol
		(lib_id "antmicroCapacitors0402:C_470n_0402")
		(at 104.14 190.5 0)
		(mirror x)
		(unit 1)
		(exclude_from_sim no)
		(in_bom yes)
		(on_board yes)
		(dnp no)
		(property "Reference" "C59"
			(at 103.505 191.77 0)
			(effects
				(font
					(size 1.27 1.27)
					(thickness 0.15)
				)
			)
		)
		(property "Value" "C_470n_0402"
			(at 124.46 180.34 0)
			(effects
				(font
					(size 1.27 1.27)
					(thickness 0.15)
				)
				(justify left bottom)
				(hide yes)
			)
		)
		(property "Footprint" "antmicro-footprints:C_0402_1005Metric"
			(at 124.46 177.8 0)
			(effects
				(font
					(size 1.27 1.27)
					(thickness 0.15)
				)
				(justify left bottom)
				(hide yes)
			)
		)
		(property "Datasheet" "https://product.tdk.com/en/search/capacitor/ceramic/mlcc/info?part_no=C1005X5R1E474M050BB"
			(at 124.46 175.26 0)
			(effects
				(font
					(size 1.27 1.27)
					(thickness 0.15)
				)
				(justify left bottom)
				(hide yes)
			)
		)
		(property "Description" "SMD Multilayer Ceramic Capacitor, 0.47 µF, 25 V, 0402 [1005 Metric], ± 20%, X5R, C"
			(at 104.14 190.5 0)
			(effects
				(font
					(size 1.27 1.27)
				)
				(hide yes)
			)
		)
		(property "Manufacturer" "TDK"
			(at 124.46 170.18 0)
			(effects
				(font
					(size 1.27 1.27)
					(thickness 0.15)
				)
				(justify left bottom)
				(hide yes)
			)
		)
		(property "MPN" "C1005X5R1E474M050BB"
			(at 124.46 172.72 0)
			(effects
				(font
					(size 1.27 1.27)
					(thickness 0.15)
				)
				(justify left bottom)
				(hide yes)
			)
		)
		(property "Val" "470n"
			(at 109.855 191.77 0)
			(effects
				(font
					(size 1.27 1.27)
					(thickness 0.15)
				)
			)
		)
		(property "License" "Apache-2.0"
			(at 124.46 167.64 0)
			(effects
				(font
					(size 1.27 1.27)
					(thickness 0.15)
				)
				(justify left bottom)
				(hide yes)
			)
		)
		(property "Author" "Antmicro"
			(at 124.46 165.1 0)
			(effects
				(font
					(size 1.27 1.27)
					(thickness 0.15)
				)
				(justify left bottom)
				(hide yes)
			)
		)
		(property "Voltage" ""
			(at 124.46 162.56 0)
			(effects
				(font
					(size 1.27 1.27)
				)
				(justify left bottom)
				(hide yes)
			)
		)
		(property "Dielectric" ""
			(at 124.46 160.02 0)
			(effects
				(font
					(size 1.27 1.27)
				)
				(justify left bottom)
				(hide yes)
			)
		)
		(pin "1"
		)
		(pin "2"
		)
		(instances
			(project "sdi-mipi-video-converter"
				(path ""
					(reference "C59")
					(unit 1)
				)
			)
		)
	)
	(symbol
		(lib_id "antmicroResistors0402:R_100k_0402")
		(at 106.68 167.64 0)
		(unit 1)
		(exclude_from_sim no)
		(in_bom yes)
		(on_board yes)
		(dnp no)
		(fields_autoplaced yes)
		(property "Reference" "R54"
			(at 109.22 161.29 0)
			(effects
				(font
					(size 1.27 1.27)
					(thickness 0.15)
				)
			)
		)
		(property "Value" "R_100k_0402"
			(at 127 180.34 0)
			(effects
				(font
					(size 1.27 1.27)
					(thickness 0.15)
				)
				(justify left bottom)
				(hide yes)
			)
		)
		(property "Footprint" "antmicro-footprints:R_0402_1005Metric"
			(at 127 182.88 0)
			(effects
				(font
					(size 1.27 1.27)
					(thickness 0.15)
				)
				(justify left bottom)
				(hide yes)
			)
		)
		(property "Datasheet" "https://www.bourns.com/docs/product-datasheets/cr.pdf"
			(at 127 185.42 0)
			(effects
				(font
					(size 1.27 1.27)
					(thickness 0.15)
				)
				(justify left bottom)
				(hide yes)
			)
		)
		(property "Description" "SMD Chip Resistor, 100 kohm, ± 1%, 62.5 mW, 0402 [1005 Metric], Thick Film, General Purpose"
			(at 106.68 167.64 0)
			(effects
				(font
					(size 1.27 1.27)
				)
				(hide yes)
			)
		)
		(property "Manufacturer" "Bourns"
			(at 127 190.5 0)
			(effects
				(font
					(size 1.27 1.27)
					(thickness 0.15)
				)
				(justify left bottom)
				(hide yes)
			)
		)
		(property "MPN" "CR0402-FX-1003GLF"
			(at 127 187.96 0)
			(effects
				(font
					(size 1.27 1.27)
					(thickness 0.15)
				)
				(justify left bottom)
				(hide yes)
			)
		)
		(property "Val" "100k"
			(at 109.22 163.83 0)
			(effects
				(font
					(size 1.27 1.27)
					(thickness 0.15)
				)
			)
		)
		(property "License" "Apache-2.0"
			(at 127 193.04 0)
			(effects
				(font
					(size 1.27 1.27)
					(thickness 0.15)
				)
				(justify left bottom)
				(hide yes)
			)
		)
		(property "Author" "Antmicro"
			(at 127 195.58 0)
			(effects
				(font
					(size 1.27 1.27)
					(thickness 0.15)
				)
				(justify left bottom)
				(hide yes)
			)
		)
		(property "Tolerance" "1%"
			(at 127 177.8 0)
			(effects
				(font
					(size 1.27 1.27)
				)
				(justify left bottom)
				(hide yes)
			)
		)
		(pin "1"
		)
		(pin "2"
		)
		(instances
			(project "sdi-mipi-video-converter"
				(path ""
					(reference "R54")
					(unit 1)
				)
			)
		)
	)
	(symbol
		(lib_id "antmicropower:+3.3V")
		(at 289.56 71.12 0)
		(unit 1)
		(exclude_from_sim no)
		(in_bom yes)
		(on_board yes)
		(dnp no)
		(fields_autoplaced yes)
		(property "Reference" "#PWR0140"
			(at 289.56 74.93 0)
			(effects
				(font
					(size 1.27 1.27)
				)
				(hide yes)
			)
		)
		(property "Value" "+3V3"
			(at 289.56 66.04 0)
			(effects
				(font
					(size 1.27 1.27)
				)
			)
		)
		(property "Footprint" ""
			(at 289.56 71.12 0)
			(effects
				(font
					(size 1.27 1.27)
				)
				(hide yes)
			)
		)
		(property "Datasheet" ""
			(at 289.56 71.12 0)
			(effects
				(font
					(size 1.27 1.27)
				)
				(hide yes)
			)
		)
		(property "Description" ""
			(at 289.56 71.12 0)
			(effects
				(font
					(size 1.27 1.27)
				)
				(hide yes)
			)
		)
		(pin "1"
		)
		(instances
			(project "sdi-mipi-video-converter"
				(path ""
					(reference "#PWR0140")
					(unit 1)
				)
			)
		)
	)
	(symbol
		(lib_id "antmicroResistors0402:R_37R4_0402")
		(at 73.66 208.28 270)
		(unit 1)
		(exclude_from_sim no)
		(in_bom yes)
		(on_board yes)
		(dnp no)
		(fields_autoplaced yes)
		(property "Reference" "R53"
			(at 76.2 209.5499 90)
			(effects
				(font
					(size 1.27 1.27)
					(thickness 0.15)
				)
				(justify left)
			)
		)
		(property "Value" "R_37R4_0402"
			(at 60.96 228.6 0)
			(effects
				(font
					(size 1.27 1.27)
					(thickness 0.15)
				)
				(justify left bottom)
				(hide yes)
			)
		)
		(property "Footprint" "antmicro-footprints:R_0402_1005Metric"
			(at 58.42 228.6 0)
			(effects
				(font
					(size 1.27 1.27)
					(thickness 0.15)
				)
				(justify left bottom)
				(hide yes)
			)
		)
		(property "Datasheet" "https://www.bourns.com/docs/product-datasheets/cr.pdf"
			(at 55.88 228.6 0)
			(effects
				(font
					(size 1.27 1.27)
					(thickness 0.15)
				)
				(justify left bottom)
				(hide yes)
			)
		)
		(property "Description" "SMD Chip Resistor, 37.4 ohm, ± 1%, 100 mW, 0402 [1005 Metric], Thick Film, Precision"
			(at 73.66 208.28 0)
			(effects
				(font
					(size 1.27 1.27)
				)
				(hide yes)
			)
		)
		(property "Manufacturer" "Bourns"
			(at 50.8 228.6 0)
			(effects
				(font
					(size 1.27 1.27)
					(thickness 0.15)
				)
				(justify left bottom)
				(hide yes)
			)
		)
		(property "MPN" "CR0402-FX-37R4GLF"
			(at 53.34 228.6 0)
			(effects
				(font
					(size 1.27 1.27)
					(thickness 0.15)
				)
				(justify left bottom)
				(hide yes)
			)
		)
		(property "Val" "37R4"
			(at 76.2 212.0899 90)
			(effects
				(font
					(size 1.27 1.27)
					(thickness 0.15)
				)
				(justify left)
			)
		)
		(property "License" "Apache-2.0"
			(at 48.26 228.6 0)
			(effects
				(font
					(size 1.27 1.27)
					(thickness 0.15)
				)
				(justify left bottom)
				(hide yes)
			)
		)
		(property "Author" "Antmicro"
			(at 45.72 228.6 0)
			(effects
				(font
					(size 1.27 1.27)
					(thickness 0.15)
				)
				(justify left bottom)
				(hide yes)
			)
		)
		(property "Tolerance" "1%"
			(at 63.5 228.6 0)
			(effects
				(font
					(size 1.27 1.27)
				)
				(justify left bottom)
				(hide yes)
			)
		)
		(pin "1"
		)
		(pin "2"
		)
		(instances
			(project "sdi-mipi-video-converter"
				(path ""
					(reference "R53")
					(unit 1)
				)
			)
		)
	)
	(symbol
		(lib_id "antmicropower:GND")
		(at 270.51 218.44 0)
		(unit 1)
		(exclude_from_sim no)
		(in_bom yes)
		(on_board yes)
		(dnp no)
		(fields_autoplaced yes)
		(property "Reference" "#PWR0137"
			(at 279.4 220.98 0)
			(effects
				(font
					(size 1.27 1.27)
					(thickness 0.15)
				)
				(justify left bottom)
				(hide yes)
			)
		)
		(property "Value" "GND"
			(at 267.97 219.7099 0)
			(effects
				(font
					(size 1.27 1.27)
					(thickness 0.15)
				)
				(justify right)
			)
		)
		(property "Footprint" ""
			(at 279.4 226.06 0)
			(effects
				(font
					(size 1.27 1.27)
					(thickness 0.15)
				)
				(justify left bottom)
				(hide yes)
			)
		)
		(property "Datasheet" ""
			(at 279.4 231.14 0)
			(effects
				(font
					(size 1.27 1.27)
					(thickness 0.15)
				)
				(justify left bottom)
				(hide yes)
			)
		)
		(property "Description" ""
			(at 270.51 218.44 0)
			(effects
				(font
					(size 1.27 1.27)
				)
				(hide yes)
			)
		)
		(property "Author" "Antmicro"
			(at 279.4 226.06 0)
			(effects
				(font
					(size 1.27 1.27)
					(thickness 0.15)
				)
				(justify left bottom)
				(hide yes)
			)
		)
		(property "License" "Apache-2.0"
			(at 279.4 228.6 0)
			(effects
				(font
					(size 1.27 1.27)
					(thickness 0.15)
				)
				(justify left bottom)
				(hide yes)
			)
		)
		(pin "1"
		)
		(instances
			(project "sdi-mipi-video-converter"
				(path ""
					(reference "#PWR0137")
					(unit 1)
				)
			)
		)
	)
	(symbol
		(lib_id "antmicropower:GND")
		(at 151.13 259.08 0)
		(unit 1)
		(exclude_from_sim no)
		(in_bom yes)
		(on_board yes)
		(dnp no)
		(property "Reference" "#PWR0247"
			(at 160.02 261.62 0)
			(effects
				(font
					(size 1.27 1.27)
					(thickness 0.15)
				)
				(justify left bottom)
				(hide yes)
			)
		)
		(property "Value" "GND"
			(at 151.13 262.89 0)
			(effects
				(font
					(size 1.27 1.27)
					(thickness 0.15)
				)
			)
		)
		(property "Footprint" ""
			(at 160.02 266.7 0)
			(effects
				(font
					(size 1.27 1.27)
					(thickness 0.15)
				)
				(justify left bottom)
				(hide yes)
			)
		)
		(property "Datasheet" ""
			(at 160.02 271.78 0)
			(effects
				(font
					(size 1.27 1.27)
					(thickness 0.15)
				)
				(justify left bottom)
				(hide yes)
			)
		)
		(property "Description" ""
			(at 151.13 259.08 0)
			(effects
				(font
					(size 1.27 1.27)
				)
				(hide yes)
			)
		)
		(property "Author" "Antmicro"
			(at 160.02 266.7 0)
			(effects
				(font
					(size 1.27 1.27)
					(thickness 0.15)
				)
				(justify left bottom)
				(hide yes)
			)
		)
		(property "License" "Apache-2.0"
			(at 160.02 269.24 0)
			(effects
				(font
					(size 1.27 1.27)
					(thickness 0.15)
				)
				(justify left bottom)
				(hide yes)
			)
		)
		(pin "1"
		)
		(instances
			(project "sdi-mipi-video-converter"
				(path ""
					(reference "#PWR0247")
					(unit 1)
				)
			)
		)
	)
	(symbol
		(lib_id "antmicropower:GND")
		(at 259.08 257.81 0)
		(unit 1)
		(exclude_from_sim no)
		(in_bom yes)
		(on_board yes)
		(dnp no)
		(fields_autoplaced yes)
		(property "Reference" "#PWR0133"
			(at 267.97 260.35 0)
			(effects
				(font
					(size 1.27 1.27)
					(thickness 0.15)
				)
				(justify left bottom)
				(hide yes)
			)
		)
		(property "Value" "GND"
			(at 256.54 259.0799 0)
			(effects
				(font
					(size 1.27 1.27)
					(thickness 0.15)
				)
				(justify right)
			)
		)
		(property "Footprint" ""
			(at 267.97 265.43 0)
			(effects
				(font
					(size 1.27 1.27)
					(thickness 0.15)
				)
				(justify left bottom)
				(hide yes)
			)
		)
		(property "Datasheet" ""
			(at 267.97 270.51 0)
			(effects
				(font
					(size 1.27 1.27)
					(thickness 0.15)
				)
				(justify left bottom)
				(hide yes)
			)
		)
		(property "Description" ""
			(at 259.08 257.81 0)
			(effects
				(font
					(size 1.27 1.27)
				)
				(hide yes)
			)
		)
		(property "Author" "Antmicro"
			(at 267.97 265.43 0)
			(effects
				(font
					(size 1.27 1.27)
					(thickness 0.15)
				)
				(justify left bottom)
				(hide yes)
			)
		)
		(property "License" "Apache-2.0"
			(at 267.97 267.97 0)
			(effects
				(font
					(size 1.27 1.27)
					(thickness 0.15)
				)
				(justify left bottom)
				(hide yes)
			)
		)
		(pin "1"
		)
		(instances
			(project "sdi-mipi-video-converter"
				(path ""
					(reference "#PWR0133")
					(unit 1)
				)
			)
		)
	)
	(symbol
		(lib_id "antmicroTestPoints:TP_0.75mm_SMD")
		(at 194.31 175.26 0)
		(unit 1)
		(exclude_from_sim no)
		(in_bom yes)
		(on_board yes)
		(dnp no)
		(fields_autoplaced yes)
		(property "Reference" "TP31"
			(at 199.39 175.2599 0)
			(effects
				(font
					(size 1.27 1.27)
					(thickness 0.15)
				)
				(justify left)
			)
		)
		(property "Value" "TP_0.75mm_SMD"
			(at 212.09 182.88 0)
			(effects
				(font
					(size 1.27 1.27)
					(thickness 0.15)
				)
				(justify left bottom)
				(hide yes)
			)
		)
		(property "Footprint" "antmicro-footprints:TP_SMD_0.75mm"
			(at 212.09 185.42 0)
			(effects
				(font
					(size 1.27 1.27)
					(thickness 0.15)
				)
				(justify left bottom)
				(hide yes)
			)
		)
		(property "Datasheet" ""
			(at 212.09 187.96 0)
			(effects
				(font
					(size 1.27 1.27)
					(thickness 0.15)
				)
				(justify left bottom)
				(hide yes)
			)
		)
		(property "Description" "SMT test point"
			(at 194.31 175.26 0)
			(effects
				(font
					(size 1.27 1.27)
				)
				(hide yes)
			)
		)
		(property "MPN" ""
			(at 212.09 190.5 0)
			(effects
				(font
					(size 1.27 1.27)
					(thickness 0.15)
				)
				(justify left bottom)
				(hide yes)
			)
		)
		(property "Manufacturer" ""
			(at 212.09 193.04 0)
			(effects
				(font
					(size 1.27 1.27)
					(thickness 0.15)
				)
				(justify left bottom)
				(hide yes)
			)
		)
		(property "Author" "Antmicro"
			(at 212.09 195.58 0)
			(effects
				(font
					(size 1.27 1.27)
					(thickness 0.15)
				)
				(justify left bottom)
				(hide yes)
			)
		)
		(property "License" "Apache-2.0"
			(at 212.09 198.12 0)
			(effects
				(font
					(size 1.27 1.27)
					(thickness 0.15)
				)
				(justify left bottom)
				(hide yes)
			)
		)
		(pin "1"
		)
		(instances
			(project "sdi-mipi-video-converter"
				(path ""
					(reference "TP31")
					(unit 1)
				)
			)
		)
	)
	(symbol
		(lib_id "antmicroCapacitors0402:C_100n_0402")
		(at 247.65 237.49 90)
		(unit 1)
		(exclude_from_sim no)
		(in_bom yes)
		(on_board yes)
		(dnp no)
		(fields_autoplaced yes)
		(property "Reference" "C63"
			(at 250.19 233.6735 90)
			(effects
				(font
					(size 1.27 1.27)
					(thickness 0.15)
				)
				(justify right)
			)
		)
		(property "Value" "C_100n_0402"
			(at 257.81 217.17 0)
			(effects
				(font
					(size 1.27 1.27)
					(thickness 0.15)
				)
				(justify left bottom)
				(hide yes)
			)
		)
		(property "Footprint" "antmicro-footprints:C_0402_1005Metric"
			(at 260.35 217.17 0)
			(effects
				(font
					(size 1.27 1.27)
					(thickness 0.15)
				)
				(justify left bottom)
				(hide yes)
			)
		)
		(property "Datasheet" "https://www.murata.com/products/productdetail?partno=GRM155R61H104KE14%23"
			(at 262.89 217.17 0)
			(effects
				(font
					(size 1.27 1.27)
					(thickness 0.15)
				)
				(justify left bottom)
				(hide yes)
			)
		)
		(property "Description" "SMD Multilayer Ceramic Capacitor, 0.1 µF, 50 V, 0402 [1005 Metric], ± 10%, X5R, GRM Series"
			(at 247.65 237.49 0)
			(effects
				(font
					(size 1.27 1.27)
				)
				(hide yes)
			)
		)
		(property "Manufacturer" "Murata"
			(at 267.97 217.17 0)
			(effects
				(font
					(size 1.27 1.27)
					(thickness 0.15)
				)
				(justify left bottom)
				(hide yes)
			)
		)
		(property "MPN" "GRM155R61H104KE14D"
			(at 265.43 217.17 0)
			(effects
				(font
					(size 1.27 1.27)
					(thickness 0.15)
				)
				(justify left bottom)
				(hide yes)
			)
		)
		(property "Val" "100n"
			(at 250.19 236.2135 90)
			(effects
				(font
					(size 1.27 1.27)
					(thickness 0.15)
				)
				(justify right)
			)
		)
		(property "License" "Apache-2.0"
			(at 270.51 217.17 0)
			(effects
				(font
					(size 1.27 1.27)
					(thickness 0.15)
				)
				(justify left bottom)
				(hide yes)
			)
		)
		(property "Author" "Antmicro"
			(at 273.05 217.17 0)
			(effects
				(font
					(size 1.27 1.27)
					(thickness 0.15)
				)
				(justify left bottom)
				(hide yes)
			)
		)
		(property "Voltage" "50V"
			(at 275.59 217.17 0)
			(effects
				(font
					(size 1.27 1.27)
				)
				(justify left bottom)
				(hide yes)
			)
		)
		(property "Dielectric" "X5R"
			(at 278.13 217.17 0)
			(effects
				(font
					(size 1.27 1.27)
				)
				(justify left bottom)
				(hide yes)
			)
		)
		(pin "1"
		)
		(pin "2"
		)
		(instances
			(project "sdi-mipi-video-converter"
				(path ""
					(reference "C63")
					(unit 1)
				)
			)
		)
	)
	(symbol
		(lib_id "antmicropower:GND")
		(at 266.7 176.53 0)
		(unit 1)
		(exclude_from_sim no)
		(in_bom yes)
		(on_board yes)
		(dnp no)
		(fields_autoplaced yes)
		(property "Reference" "#PWR0135"
			(at 275.59 179.07 0)
			(effects
				(font
					(size 1.27 1.27)
					(thickness 0.15)
				)
				(justify left bottom)
				(hide yes)
			)
		)
		(property "Value" "GND"
			(at 266.7 181.61 0)
			(effects
				(font
					(size 1.27 1.27)
					(thickness 0.15)
				)
			)
		)
		(property "Footprint" ""
			(at 275.59 184.15 0)
			(effects
				(font
					(size 1.27 1.27)
					(thickness 0.15)
				)
				(justify left bottom)
				(hide yes)
			)
		)
		(property "Datasheet" ""
			(at 275.59 189.23 0)
			(effects
				(font
					(size 1.27 1.27)
					(thickness 0.15)
				)
				(justify left bottom)
				(hide yes)
			)
		)
		(property "Description" ""
			(at 266.7 176.53 0)
			(effects
				(font
					(size 1.27 1.27)
				)
				(hide yes)
			)
		)
		(property "Author" "Antmicro"
			(at 275.59 184.15 0)
			(effects
				(font
					(size 1.27 1.27)
					(thickness 0.15)
				)
				(justify left bottom)
				(hide yes)
			)
		)
		(property "License" "Apache-2.0"
			(at 275.59 186.69 0)
			(effects
				(font
					(size 1.27 1.27)
					(thickness 0.15)
				)
				(justify left bottom)
				(hide yes)
			)
		)
		(pin "1"
		)
		(instances
			(project "sdi-mipi-video-converter"
				(path ""
					(reference "#PWR0135")
					(unit 1)
				)
			)
		)
	)
	(symbol
		(lib_id "antmicroCapacitors0402:C_100n_0402")
		(at 247.65 217.17 90)
		(unit 1)
		(exclude_from_sim no)
		(in_bom yes)
		(on_board yes)
		(dnp no)
		(fields_autoplaced yes)
		(property "Reference" "C62"
			(at 250.19 213.3535 90)
			(effects
				(font
					(size 1.27 1.27)
					(thickness 0.15)
				)
				(justify right)
			)
		)
		(property "Value" "C_100n_0402"
			(at 257.81 196.85 0)
			(effects
				(font
					(size 1.27 1.27)
					(thickness 0.15)
				)
				(justify left bottom)
				(hide yes)
			)
		)
		(property "Footprint" "antmicro-footprints:C_0402_1005Metric"
			(at 260.35 196.85 0)
			(effects
				(font
					(size 1.27 1.27)
					(thickness 0.15)
				)
				(justify left bottom)
				(hide yes)
			)
		)
		(property "Datasheet" "https://www.murata.com/products/productdetail?partno=GRM155R61H104KE14%23"
			(at 262.89 196.85 0)
			(effects
				(font
					(size 1.27 1.27)
					(thickness 0.15)
				)
				(justify left bottom)
				(hide yes)
			)
		)
		(property "Description" "SMD Multilayer Ceramic Capacitor, 0.1 µF, 50 V, 0402 [1005 Metric], ± 10%, X5R, GRM Series"
			(at 247.65 217.17 0)
			(effects
				(font
					(size 1.27 1.27)
				)
				(hide yes)
			)
		)
		(property "Manufacturer" "Murata"
			(at 267.97 196.85 0)
			(effects
				(font
					(size 1.27 1.27)
					(thickness 0.15)
				)
				(justify left bottom)
				(hide yes)
			)
		)
		(property "MPN" "GRM155R61H104KE14D"
			(at 265.43 196.85 0)
			(effects
				(font
					(size 1.27 1.27)
					(thickness 0.15)
				)
				(justify left bottom)
				(hide yes)
			)
		)
		(property "Val" "100n"
			(at 250.19 215.8935 90)
			(effects
				(font
					(size 1.27 1.27)
					(thickness 0.15)
				)
				(justify right)
			)
		)
		(property "License" "Apache-2.0"
			(at 270.51 196.85 0)
			(effects
				(font
					(size 1.27 1.27)
					(thickness 0.15)
				)
				(justify left bottom)
				(hide yes)
			)
		)
		(property "Author" "Antmicro"
			(at 273.05 196.85 0)
			(effects
				(font
					(size 1.27 1.27)
					(thickness 0.15)
				)
				(justify left bottom)
				(hide yes)
			)
		)
		(property "Voltage" "50V"
			(at 275.59 196.85 0)
			(effects
				(font
					(size 1.27 1.27)
				)
				(justify left bottom)
				(hide yes)
			)
		)
		(property "Dielectric" "X5R"
			(at 278.13 196.85 0)
			(effects
				(font
					(size 1.27 1.27)
				)
				(justify left bottom)
				(hide yes)
			)
		)
		(pin "1"
		)
		(pin "2"
		)
		(instances
			(project "sdi-mipi-video-converter"
				(path ""
					(reference "C62")
					(unit 1)
				)
			)
		)
	)
	(symbol
		(lib_id "antmicroCapacitorspol:C_Pol_33u_4V_KYOCERA-AVX-F98-0603")
		(at 266.7 170.18 270)
		(unit 1)
		(exclude_from_sim no)
		(in_bom yes)
		(on_board yes)
		(dnp no)
		(fields_autoplaced yes)
		(property "Reference" "C71"
			(at 269.24 170.9166 90)
			(effects
				(font
					(size 1.27 1.27)
					(thickness 0.15)
				)
				(justify left)
			)
		)
		(property "Value" "C_33u_0603"
			(at 261.62 184.15 0)
			(effects
				(font
					(size 1.27 1.27)
					(thickness 0.15)
				)
				(justify left bottom)
				(hide yes)
			)
		)
		(property "Footprint" "antmicro-footprints:C_Pol_0603_1608Metric"
			(at 259.08 184.15 0)
			(effects
				(font
					(size 1.27 1.27)
					(thickness 0.15)
				)
				(justify left bottom)
				(hide yes)
			)
		)
		(property "Datasheet" "https://spicat.kyocera-avx.com/product/tan/chartview/F980G336MMA/"
			(at 256.54 184.15 0)
			(effects
				(font
					(size 1.27 1.27)
					(thickness 0.15)
				)
				(justify left bottom)
				(hide yes)
			)
		)
		(property "Description" "Surface Mount Tantalum Capacitor, 33 µF, 4 V, 0603 [1608 Metric], ± 20%, 4 ohm, M"
			(at 266.7 170.18 0)
			(effects
				(font
					(size 1.27 1.27)
				)
				(hide yes)
			)
		)
		(property "Manufacturer" "KYOCERA AVX"
			(at 251.46 184.15 0)
			(effects
				(font
					(size 1.27 1.27)
					(thickness 0.15)
				)
				(justify left bottom)
				(hide yes)
			)
		)
		(property "MPN" "F980G336MMA"
			(at 254 184.15 0)
			(effects
				(font
					(size 1.27 1.27)
					(thickness 0.15)
				)
				(justify left bottom)
				(hide yes)
			)
		)
		(property "Val" "33u"
			(at 269.24 173.4566 90)
			(effects
				(font
					(size 1.27 1.27)
					(thickness 0.15)
				)
				(justify left)
			)
		)
		(property "License" "Apache-2.0"
			(at 248.92 184.15 0)
			(effects
				(font
					(size 1.27 1.27)
					(thickness 0.15)
				)
				(justify left bottom)
				(hide yes)
			)
		)
		(property "Author" "Antmicro"
			(at 246.38 184.15 0)
			(effects
				(font
					(size 1.27 1.27)
					(thickness 0.15)
				)
				(justify left bottom)
				(hide yes)
			)
		)
		(property "Voltage" "4V"
			(at 243.84 184.15 0)
			(effects
				(font
					(size 1.27 1.27)
				)
				(justify left bottom)
				(hide yes)
			)
		)
		(property "Dielectric" "template_dielectric"
			(at 241.3 184.15 0)
			(effects
				(font
					(size 1.27 1.27)
				)
				(justify left bottom)
				(hide yes)
			)
		)
		(pin "1"
		)
		(pin "2"
		)
		(instances
			(project "sdi-mipi-video-converter"
				(path ""
					(reference "C71")
					(unit 1)
				)
			)
		)
	)
	(symbol
		(lib_id "antmicroInterfaceControllers:GS2971A")
		(at 120.65 226.06 0)
		(mirror y)
		(unit 1)
		(exclude_from_sim no)
		(in_bom yes)
		(on_board yes)
		(dnp no)
		(fields_autoplaced yes)
		(property "Reference" "U15"
			(at 107.315 218.44 0)
			(effects
				(font
					(size 1.27 1.27)
					(thickness 0.15)
				)
			)
		)
		(property "Value" "GS2971A"
			(at 107.315 220.98 0)
			(effects
				(font
					(size 1.27 1.27)
					(thickness 0.15)
				)
			)
		)
		(property "Footprint" "antmicro-footprints:BGA-100_11x11mm_Layout10x10_P1mm"
			(at 64.77 233.68 0)
			(effects
				(font
					(size 1.27 1.27)
					(thickness 0.15)
				)
				(justify left bottom)
				(hide yes)
			)
		)
		(property "Datasheet" "https://semtech.my.salesforce.com/sfc/p/#E0000000JelG/a/44000000MD3i/kpmMkrmUWgHlbCOwdLzVohMm1SDPoVH85guEGK.KXTc"
			(at 64.77 236.22 0)
			(effects
				(font
					(size 1.27 1.27)
					(thickness 0.15)
				)
				(justify left bottom)
				(hide yes)
			)
		)
		(property "Description" "SDI receiver"
			(at 120.65 226.06 0)
			(effects
				(font
					(size 1.27 1.27)
				)
				(hide yes)
			)
		)
		(property "MPN" "GS2971A"
			(at 64.77 238.76 0)
			(effects
				(font
					(size 1.27 1.27)
					(thickness 0.15)
				)
				(justify left bottom)
				(hide yes)
			)
		)
		(property "Manufacturer" "Semtech"
			(at 64.77 241.3 0)
			(effects
				(font
					(size 1.27 1.27)
					(thickness 0.15)
				)
				(justify left bottom)
				(hide yes)
			)
		)
		(property "Author" "Antmicro"
			(at 64.77 243.84 0)
			(effects
				(font
					(size 1.27 1.27)
					(thickness 0.15)
				)
				(justify left bottom)
				(hide yes)
			)
		)
		(property "License" "Apache-2.0"
			(at 64.77 246.38 0)
			(effects
				(font
					(size 1.27 1.27)
					(thickness 0.15)
				)
				(justify left bottom)
				(hide yes)
			)
		)
		(pin "A10"
		)
		(pin "A5"
		)
		(pin "A6"
		)
		(pin "A8"
		)
		(pin "A9"
		)
		(pin "B10"
		)
		(pin "B5"
		)
		(pin "B6"
		)
		(pin "B8"
		)
		(pin "B9"
		)
		(pin "C10"
		)
		(pin "C5"
		)
		(pin "C6"
		)
		(pin "C8"
		)
		(pin "C9"
		)
		(pin "E10"
		)
		(pin "E9"
		)
		(pin "F10"
		)
		(pin "F9"
		)
		(pin "H10"
		)
		(pin "H4"
		)
		(pin "H9"
		)
		(pin "J1"
		)
		(pin "J10"
		)
		(pin "J3"
		)
		(pin "J4"
		)
		(pin "J5"
		)
		(pin "J8"
		)
		(pin "J9"
		)
		(pin "K1"
		)
		(pin "K10"
		)
		(pin "K3"
		)
		(pin "K4"
		)
		(pin "K5"
		)
		(pin "K8"
		)
		(pin "K9"
		)
		(pin "A1"
		)
		(pin "A2"
		)
		(pin "A3"
		)
		(pin "B3"
		)
		(pin "C1"
		)
		(pin "C7"
		)
		(pin "D1"
		)
		(pin "D7"
		)
		(pin "D8"
		)
		(pin "E7"
		)
		(pin "E8"
		)
		(pin "F1"
		)
		(pin "F2"
		)
		(pin "F7"
		)
		(pin "F8"
		)
		(pin "G1"
		)
		(pin "G3"
		)
		(pin "G7"
		)
		(pin "G8"
		)
		(pin "H3"
		)
		(pin "H5"
		)
		(pin "H6"
		)
		(pin "H7"
		)
		(pin "H8"
		)
		(pin "J2"
		)
		(pin "J6"
		)
		(pin "K2"
		)
		(pin "K6"
		)
		(pin "A4"
		)
		(pin "A7"
		)
		(pin "B1"
		)
		(pin "B2"
		)
		(pin "B4"
		)
		(pin "B7"
		)
		(pin "C2"
		)
		(pin "C3"
		)
		(pin "C4"
		)
		(pin "D10"
		)
		(pin "D2"
		)
		(pin "D3"
		)
		(pin "D4"
		)
		(pin "D5"
		)
		(pin "D6"
		)
		(pin "D9"
		)
		(pin "E1"
		)
		(pin "E2"
		)
		(pin "E3"
		)
		(pin "E4"
		)
		(pin "E5"
		)
		(pin "E6"
		)
		(pin "F3"
		)
		(pin "F4"
		)
		(pin "F5"
		)
		(pin "F6"
		)
		(pin "G10"
		)
		(pin "G2"
		)
		(pin "G4"
		)
		(pin "G5"
		)
		(pin "G6"
		)
		(pin "G9"
		)
		(pin "H1"
		)
		(pin "H2"
		)
		(pin "J7"
		)
		(pin "K7"
		)
		(instances
			(project "sdi-mipi-video-converter"
				(path ""
					(reference "U15")
					(unit 1)
				)
			)
		)
	)
	(symbol
		(lib_id "antmicroFixedInductors:L_6n2_0.7A_0402")
		(at 331.47 99.06 0)
		(mirror y)
		(unit 1)
		(exclude_from_sim no)
		(in_bom yes)
		(on_board yes)
		(dnp no)
		(fields_autoplaced yes)
		(property "Reference" "L5"
			(at 328.93 101.6 0)
			(effects
				(font
					(size 1.27 1.27)
					(thickness 0.15)
				)
			)
		)
		(property "Value" "L_6n2_0.7A_0402"
			(at 317.5 101.6 0)
			(effects
				(font
					(size 1.27 1.27)
					(thickness 0.15)
				)
				(justify left bottom)
				(hide yes)
			)
		)
		(property "Footprint" "antmicro-footprints:L_0402_1005Metric"
			(at 317.5 106.68 0)
			(effects
				(font
					(size 1.27 1.27)
					(thickness 0.15)
				)
				(justify left bottom)
				(hide yes)
			)
		)
		(property "Datasheet" "https://www.mouser.com/datasheet/2/281/1/JELF243A_0050-1380872.pdf"
			(at 317.5 109.22 0)
			(effects
				(font
					(size 1.27 1.27)
					(thickness 0.15)
				)
				(justify left bottom)
				(hide yes)
			)
		)
		(property "Description" "Wirewound Inductor, 6.2 nH, 0.09 ohm, 8 GHz, 700 mA, 0402 [1005 Metric], LQW"
			(at 331.47 99.06 0)
			(effects
				(font
					(size 1.27 1.27)
				)
				(hide yes)
			)
		)
		(property "MPN" "LQW15AN6N2C00D"
			(at 317.5 114.3 0)
			(effects
				(font
					(size 1.27 1.27)
					(thickness 0.15)
				)
				(justify left bottom)
				(hide yes)
			)
		)
		(property "Manufacturer" "Murata"
			(at 317.5 111.76 0)
			(effects
				(font
					(size 1.27 1.27)
					(thickness 0.15)
				)
				(justify left bottom)
				(hide yes)
			)
		)
		(property "Val" "6n2/0.7A"
			(at 328.93 104.14 0)
			(effects
				(font
					(size 1.27 1.27)
					(thickness 0.15)
				)
			)
		)
		(property "ISat" ""
			(at 317.5 115.57 0)
			(effects
				(font
					(size 1.27 1.27)
				)
				(justify left)
				(hide yes)
			)
		)
		(property "IMax" "0.7 A"
			(at 317.5 119.38 0)
			(effects
				(font
					(size 1.27 1.27)
					(thickness 0.15)
				)
				(justify left bottom)
				(hide yes)
			)
		)
		(property "Size" "1.0x0.5"
			(at 317.5 121.92 0)
			(effects
				(font
					(size 1.27 1.27)
					(thickness 0.15)
				)
				(justify left bottom)
				(hide yes)
			)
		)
		(property "Author" "Antmicro"
			(at 317.5 124.46 0)
			(effects
				(font
					(size 1.27 1.27)
					(thickness 0.15)
				)
				(justify left bottom)
				(hide yes)
			)
		)
		(property "License" "Apache-2.0"
			(at 317.5 127 0)
			(effects
				(font
					(size 1.27 1.27)
					(thickness 0.15)
				)
				(justify left bottom)
				(hide yes)
			)
		)
		(pin "1"
		)
		(pin "2"
		)
		(instances
			(project "sdi-mipi-video-converter"
				(path ""
					(reference "L5")
					(unit 1)
				)
			)
		)
	)
	(symbol
		(lib_id "antmicropower:GND")
		(at 182.88 186.69 0)
		(unit 1)
		(exclude_from_sim no)
		(in_bom yes)
		(on_board yes)
		(dnp no)
		(property "Reference" "#PWR0268"
			(at 191.77 189.23 0)
			(effects
				(font
					(size 1.27 1.27)
					(thickness 0.15)
				)
				(justify left bottom)
				(hide yes)
			)
		)
		(property "Value" "GND"
			(at 182.88 190.5 0)
			(effects
				(font
					(size 1.27 1.27)
					(thickness 0.15)
				)
			)
		)
		(property "Footprint" ""
			(at 191.77 194.31 0)
			(effects
				(font
					(size 1.27 1.27)
					(thickness 0.15)
				)
				(justify left bottom)
				(hide yes)
			)
		)
		(property "Datasheet" ""
			(at 191.77 199.39 0)
			(effects
				(font
					(size 1.27 1.27)
					(thickness 0.15)
				)
				(justify left bottom)
				(hide yes)
			)
		)
		(property "Description" ""
			(at 182.88 186.69 0)
			(effects
				(font
					(size 1.27 1.27)
				)
				(hide yes)
			)
		)
		(property "Author" "Antmicro"
			(at 191.77 194.31 0)
			(effects
				(font
					(size 1.27 1.27)
					(thickness 0.15)
				)
				(justify left bottom)
				(hide yes)
			)
		)
		(property "License" "Apache-2.0"
			(at 191.77 196.85 0)
			(effects
				(font
					(size 1.27 1.27)
					(thickness 0.15)
				)
				(justify left bottom)
				(hide yes)
			)
		)
		(pin "1"
		)
		(instances
			(project "sdi-mipi-video-converter"
				(path ""
					(reference "#PWR0268")
					(unit 1)
				)
			)
		)
	)
	(symbol
		(lib_id "antmicroTestPoints:TP_0.75mm_SMD")
		(at 194.31 172.72 0)
		(unit 1)
		(exclude_from_sim no)
		(in_bom yes)
		(on_board yes)
		(dnp no)
		(fields_autoplaced yes)
		(property "Reference" "TP30"
			(at 199.39 172.7199 0)
			(effects
				(font
					(size 1.27 1.27)
					(thickness 0.15)
				)
				(justify left)
			)
		)
		(property "Value" "TP_0.75mm_SMD"
			(at 212.09 180.34 0)
			(effects
				(font
					(size 1.27 1.27)
					(thickness 0.15)
				)
				(justify left bottom)
				(hide yes)
			)
		)
		(property "Footprint" "antmicro-footprints:TP_SMD_0.75mm"
			(at 212.09 182.88 0)
			(effects
				(font
					(size 1.27 1.27)
					(thickness 0.15)
				)
				(justify left bottom)
				(hide yes)
			)
		)
		(property "Datasheet" ""
			(at 212.09 185.42 0)
			(effects
				(font
					(size 1.27 1.27)
					(thickness 0.15)
				)
				(justify left bottom)
				(hide yes)
			)
		)
		(property "Description" "SMT test point"
			(at 194.31 172.72 0)
			(effects
				(font
					(size 1.27 1.27)
				)
				(hide yes)
			)
		)
		(property "MPN" ""
			(at 212.09 187.96 0)
			(effects
				(font
					(size 1.27 1.27)
					(thickness 0.15)
				)
				(justify left bottom)
				(hide yes)
			)
		)
		(property "Manufacturer" ""
			(at 212.09 190.5 0)
			(effects
				(font
					(size 1.27 1.27)
					(thickness 0.15)
				)
				(justify left bottom)
				(hide yes)
			)
		)
		(property "Author" "Antmicro"
			(at 212.09 193.04 0)
			(effects
				(font
					(size 1.27 1.27)
					(thickness 0.15)
				)
				(justify left bottom)
				(hide yes)
			)
		)
		(property "License" "Apache-2.0"
			(at 212.09 195.58 0)
			(effects
				(font
					(size 1.27 1.27)
					(thickness 0.15)
				)
				(justify left bottom)
				(hide yes)
			)
		)
		(pin "1"
		)
		(instances
			(project "sdi-mipi-video-converter"
				(path ""
					(reference "TP30")
					(unit 1)
				)
			)
		)
	)
	(symbol
		(lib_id "antmicroTestPoints:TP_0.75mm_SMD")
		(at 132.08 240.03 0)
		(unit 1)
		(exclude_from_sim no)
		(in_bom yes)
		(on_board yes)
		(dnp no)
		(fields_autoplaced yes)
		(property "Reference" "TP27"
			(at 137.16 240.0299 0)
			(effects
				(font
					(size 1.27 1.27)
					(thickness 0.15)
				)
				(justify left)
			)
		)
		(property "Value" "TP_0.75mm_SMD"
			(at 149.86 247.65 0)
			(effects
				(font
					(size 1.27 1.27)
					(thickness 0.15)
				)
				(justify left bottom)
				(hide yes)
			)
		)
		(property "Footprint" "antmicro-footprints:TP_SMD_0.75mm"
			(at 149.86 250.19 0)
			(effects
				(font
					(size 1.27 1.27)
					(thickness 0.15)
				)
				(justify left bottom)
				(hide yes)
			)
		)
		(property "Datasheet" ""
			(at 149.86 252.73 0)
			(effects
				(font
					(size 1.27 1.27)
					(thickness 0.15)
				)
				(justify left bottom)
				(hide yes)
			)
		)
		(property "Description" "SMT test point"
			(at 132.08 240.03 0)
			(effects
				(font
					(size 1.27 1.27)
				)
				(hide yes)
			)
		)
		(property "MPN" ""
			(at 149.86 255.27 0)
			(effects
				(font
					(size 1.27 1.27)
					(thickness 0.15)
				)
				(justify left bottom)
				(hide yes)
			)
		)
		(property "Manufacturer" ""
			(at 149.86 257.81 0)
			(effects
				(font
					(size 1.27 1.27)
					(thickness 0.15)
				)
				(justify left bottom)
				(hide yes)
			)
		)
		(property "Author" "Antmicro"
			(at 149.86 260.35 0)
			(effects
				(font
					(size 1.27 1.27)
					(thickness 0.15)
				)
				(justify left bottom)
				(hide yes)
			)
		)
		(property "License" "Apache-2.0"
			(at 149.86 262.89 0)
			(effects
				(font
					(size 1.27 1.27)
					(thickness 0.15)
				)
				(justify left bottom)
				(hide yes)
			)
		)
		(pin "1"
		)
		(instances
			(project "sdi-mipi-video-converter"
				(path ""
					(reference "TP27")
					(unit 1)
				)
			)
		)
	)
	(symbol
		(lib_id "antmicroTestPoints:TP_0.75mm_SMD")
		(at 118.11 182.88 180)
		(unit 1)
		(exclude_from_sim no)
		(in_bom yes)
		(on_board yes)
		(dnp no)
		(property "Reference" "TP13"
			(at 110.49 182.88 0)
			(effects
				(font
					(size 1.27 1.27)
					(thickness 0.15)
				)
			)
		)
		(property "Value" "TP_0.75mm_SMD"
			(at 100.33 175.26 0)
			(effects
				(font
					(size 1.27 1.27)
					(thickness 0.15)
				)
				(justify left bottom)
				(hide yes)
			)
		)
		(property "Footprint" "antmicro-footprints:TP_SMD_0.75mm"
			(at 100.33 172.72 0)
			(effects
				(font
					(size 1.27 1.27)
					(thickness 0.15)
				)
				(justify left bottom)
				(hide yes)
			)
		)
		(property "Datasheet" ""
			(at 100.33 170.18 0)
			(effects
				(font
					(size 1.27 1.27)
					(thickness 0.15)
				)
				(justify left bottom)
				(hide yes)
			)
		)
		(property "Description" "SMT test point"
			(at 118.11 182.88 0)
			(effects
				(font
					(size 1.27 1.27)
				)
				(hide yes)
			)
		)
		(property "MPN" ""
			(at 100.33 167.64 0)
			(effects
				(font
					(size 1.27 1.27)
					(thickness 0.15)
				)
				(justify left bottom)
				(hide yes)
			)
		)
		(property "Manufacturer" ""
			(at 100.33 165.1 0)
			(effects
				(font
					(size 1.27 1.27)
					(thickness 0.15)
				)
				(justify left bottom)
				(hide yes)
			)
		)
		(property "Author" "Antmicro"
			(at 100.33 162.56 0)
			(effects
				(font
					(size 1.27 1.27)
					(thickness 0.15)
				)
				(justify left bottom)
				(hide yes)
			)
		)
		(property "License" "Apache-2.0"
			(at 100.33 160.02 0)
			(effects
				(font
					(size 1.27 1.27)
					(thickness 0.15)
				)
				(justify left bottom)
				(hide yes)
			)
		)
		(pin "1"
		)
		(instances
			(project "sdi-mipi-video-converter"
				(path ""
					(reference "TP13")
					(unit 1)
				)
			)
		)
	)
	(symbol
		(lib_id "antmicroTestPoints:TP_0.75mm_SMD")
		(at 168.91 193.04 0)
		(unit 1)
		(exclude_from_sim no)
		(in_bom yes)
		(on_board yes)
		(dnp no)
		(fields_autoplaced yes)
		(property "Reference" "TP38"
			(at 173.99 193.0399 0)
			(effects
				(font
					(size 1.27 1.27)
					(thickness 0.15)
				)
				(justify left)
			)
		)
		(property "Value" "TP_0.75mm_SMD"
			(at 186.69 200.66 0)
			(effects
				(font
					(size 1.27 1.27)
					(thickness 0.15)
				)
				(justify left bottom)
				(hide yes)
			)
		)
		(property "Footprint" "antmicro-footprints:TP_SMD_0.75mm"
			(at 186.69 203.2 0)
			(effects
				(font
					(size 1.27 1.27)
					(thickness 0.15)
				)
				(justify left bottom)
				(hide yes)
			)
		)
		(property "Datasheet" ""
			(at 186.69 205.74 0)
			(effects
				(font
					(size 1.27 1.27)
					(thickness 0.15)
				)
				(justify left bottom)
				(hide yes)
			)
		)
		(property "Description" "SMT test point"
			(at 168.91 193.04 0)
			(effects
				(font
					(size 1.27 1.27)
				)
				(hide yes)
			)
		)
		(property "MPN" ""
			(at 186.69 208.28 0)
			(effects
				(font
					(size 1.27 1.27)
					(thickness 0.15)
				)
				(justify left bottom)
				(hide yes)
			)
		)
		(property "Manufacturer" ""
			(at 186.69 210.82 0)
			(effects
				(font
					(size 1.27 1.27)
					(thickness 0.15)
				)
				(justify left bottom)
				(hide yes)
			)
		)
		(property "Author" "Antmicro"
			(at 186.69 213.36 0)
			(effects
				(font
					(size 1.27 1.27)
					(thickness 0.15)
				)
				(justify left bottom)
				(hide yes)
			)
		)
		(property "License" "Apache-2.0"
			(at 186.69 215.9 0)
			(effects
				(font
					(size 1.27 1.27)
					(thickness 0.15)
				)
				(justify left bottom)
				(hide yes)
			)
		)
		(pin "1"
		)
		(instances
			(project "sdi-mipi-video-converter"
				(path ""
					(reference "TP38")
					(unit 1)
				)
			)
		)
	)
	(symbol
		(lib_id "antmicroCapacitors0402:C_100n_0402")
		(at 259.08 237.49 90)
		(unit 1)
		(exclude_from_sim no)
		(in_bom yes)
		(on_board yes)
		(dnp no)
		(fields_autoplaced yes)
		(property "Reference" "C68"
			(at 261.62 233.6735 90)
			(effects
				(font
					(size 1.27 1.27)
					(thickness 0.15)
				)
				(justify right)
			)
		)
		(property "Value" "C_100n_0402"
			(at 269.24 217.17 0)
			(effects
				(font
					(size 1.27 1.27)
					(thickness 0.15)
				)
				(justify left bottom)
				(hide yes)
			)
		)
		(property "Footprint" "antmicro-footprints:C_0402_1005Metric"
			(at 271.78 217.17 0)
			(effects
				(font
					(size 1.27 1.27)
					(thickness 0.15)
				)
				(justify left bottom)
				(hide yes)
			)
		)
		(property "Datasheet" "https://www.murata.com/products/productdetail?partno=GRM155R61H104KE14%23"
			(at 274.32 217.17 0)
			(effects
				(font
					(size 1.27 1.27)
					(thickness 0.15)
				)
				(justify left bottom)
				(hide yes)
			)
		)
		(property "Description" "SMD Multilayer Ceramic Capacitor, 0.1 µF, 50 V, 0402 [1005 Metric], ± 10%, X5R, GRM Series"
			(at 259.08 237.49 0)
			(effects
				(font
					(size 1.27 1.27)
				)
				(hide yes)
			)
		)
		(property "Manufacturer" "Murata"
			(at 279.4 217.17 0)
			(effects
				(font
					(size 1.27 1.27)
					(thickness 0.15)
				)
				(justify left bottom)
				(hide yes)
			)
		)
		(property "MPN" "GRM155R61H104KE14D"
			(at 276.86 217.17 0)
			(effects
				(font
					(size 1.27 1.27)
					(thickness 0.15)
				)
				(justify left bottom)
				(hide yes)
			)
		)
		(property "Val" "100n"
			(at 261.62 236.2135 90)
			(effects
				(font
					(size 1.27 1.27)
					(thickness 0.15)
				)
				(justify right)
			)
		)
		(property "License" "Apache-2.0"
			(at 281.94 217.17 0)
			(effects
				(font
					(size 1.27 1.27)
					(thickness 0.15)
				)
				(justify left bottom)
				(hide yes)
			)
		)
		(property "Author" "Antmicro"
			(at 284.48 217.17 0)
			(effects
				(font
					(size 1.27 1.27)
					(thickness 0.15)
				)
				(justify left bottom)
				(hide yes)
			)
		)
		(property "Voltage" "50V"
			(at 287.02 217.17 0)
			(effects
				(font
					(size 1.27 1.27)
				)
				(justify left bottom)
				(hide yes)
			)
		)
		(property "Dielectric" "X5R"
			(at 289.56 217.17 0)
			(effects
				(font
					(size 1.27 1.27)
				)
				(justify left bottom)
				(hide yes)
			)
		)
		(pin "1"
		)
		(pin "2"
		)
		(instances
			(project "sdi-mipi-video-converter"
				(path ""
					(reference "C68")
					(unit 1)
				)
			)
		)
	)
	(symbol
		(lib_id "antmicroCoaxialConnectorsRF:Conn_BNC_031-70526-21")
		(at 365.76 93.98 0)
		(unit 1)
		(exclude_from_sim no)
		(in_bom yes)
		(on_board yes)
		(dnp no)
		(fields_autoplaced yes)
		(property "Reference" "J3"
			(at 374.65 93.0666 0)
			(effects
				(font
					(size 1.27 1.27)
					(thickness 0.15)
				)
				(justify left)
			)
		)
		(property "Value" "Conn_BNC_031-70526-21"
			(at 374.65 95.6066 0)
			(effects
				(font
					(size 1.27 1.27)
					(thickness 0.15)
				)
				(justify left)
			)
		)
		(property "Footprint" "antmicro-footprints:Conn_BNC_031-70526-21"
			(at 386.08 104.14 0)
			(effects
				(font
					(size 1.27 1.27)
					(thickness 0.15)
				)
				(justify left bottom)
				(hide yes)
			)
		)
		(property "Datasheet" "https://www.farnell.com/cad/2305565.pdf?_ga=2.190633003.1014497200.1574067480-156563690.1566371002&_gac=1.57062104.1572875319.Cj0KCQiAtf_tBRDtARIsAIbAKe0A1M5y_jdFCiNLNrHM5L2GjmDvn_4qnRvhHAD9jBdL9AmoMNThLCoaAjhJEALw_wcB"
			(at 386.08 106.68 0)
			(effects
				(font
					(size 1.27 1.27)
					(thickness 0.15)
				)
				(justify left bottom)
				(hide yes)
			)
		)
		(property "Description" "RF / Coaxial Connector, BNC Coaxial, Straight Bulkhead Jack, Board Edge / End Launch, 75 ohm"
			(at 365.76 93.98 0)
			(effects
				(font
					(size 1.27 1.27)
				)
				(hide yes)
			)
		)
		(property "MPN" "031-70526-21"
			(at 386.08 109.22 0)
			(effects
				(font
					(size 1.27 1.27)
					(thickness 0.15)
				)
				(justify left bottom)
				(hide yes)
			)
		)
		(property "Manufacturer" "Amphenol"
			(at 386.08 111.76 0)
			(effects
				(font
					(size 1.27 1.27)
					(thickness 0.15)
				)
				(justify left bottom)
				(hide yes)
			)
		)
		(property "Author" "Antmicro"
			(at 386.08 114.3 0)
			(effects
				(font
					(size 1.27 1.27)
					(thickness 0.15)
				)
				(justify left bottom)
				(hide yes)
			)
		)
		(property "License" "Apache-2.0"
			(at 386.08 116.84 0)
			(effects
				(font
					(size 1.27 1.27)
					(thickness 0.15)
				)
				(justify left bottom)
				(hide yes)
			)
		)
		(pin "1"
		)
		(pin "2"
		)
		(instances
			(project "sdi-mipi-video-converter"
				(path ""
					(reference "J3")
					(unit 1)
				)
			)
		)
	)
	(symbol
		(lib_id "antmicropower:GND")
		(at 33.02 205.74 0)
		(unit 1)
		(exclude_from_sim no)
		(in_bom yes)
		(on_board yes)
		(dnp no)
		(fields_autoplaced yes)
		(property "Reference" "#PWR0106"
			(at 41.91 208.28 0)
			(effects
				(font
					(size 1.27 1.27)
					(thickness 0.15)
				)
				(justify left bottom)
				(hide yes)
			)
		)
		(property "Value" "GND"
			(at 33.02 210.82 0)
			(effects
				(font
					(size 1.27 1.27)
					(thickness 0.15)
				)
			)
		)
		(property "Footprint" ""
			(at 41.91 213.36 0)
			(effects
				(font
					(size 1.27 1.27)
					(thickness 0.15)
				)
				(justify left bottom)
				(hide yes)
			)
		)
		(property "Datasheet" ""
			(at 41.91 218.44 0)
			(effects
				(font
					(size 1.27 1.27)
					(thickness 0.15)
				)
				(justify left bottom)
				(hide yes)
			)
		)
		(property "Description" ""
			(at 33.02 205.74 0)
			(effects
				(font
					(size 1.27 1.27)
				)
				(hide yes)
			)
		)
		(property "Author" "Antmicro"
			(at 41.91 213.36 0)
			(effects
				(font
					(size 1.27 1.27)
					(thickness 0.15)
				)
				(justify left bottom)
				(hide yes)
			)
		)
		(property "License" "Apache-2.0"
			(at 41.91 215.9 0)
			(effects
				(font
					(size 1.27 1.27)
					(thickness 0.15)
				)
				(justify left bottom)
				(hide yes)
			)
		)
		(pin "1"
		)
		(instances
			(project "sdi-mipi-video-converter"
				(path ""
					(reference "#PWR0106")
					(unit 1)
				)
			)
		)
	)
	(symbol
		(lib_id "antmicropower:GND")
		(at 326.39 83.82 0)
		(unit 1)
		(exclude_from_sim no)
		(in_bom yes)
		(on_board yes)
		(dnp no)
		(fields_autoplaced yes)
		(property "Reference" "#PWR0145"
			(at 335.28 86.36 0)
			(effects
				(font
					(size 1.27 1.27)
					(thickness 0.15)
				)
				(justify left bottom)
				(hide yes)
			)
		)
		(property "Value" "GND"
			(at 326.39 88.9 0)
			(effects
				(font
					(size 1.27 1.27)
					(thickness 0.15)
				)
			)
		)
		(property "Footprint" ""
			(at 335.28 91.44 0)
			(effects
				(font
					(size 1.27 1.27)
					(thickness 0.15)
				)
				(justify left bottom)
				(hide yes)
			)
		)
		(property "Datasheet" ""
			(at 335.28 96.52 0)
			(effects
				(font
					(size 1.27 1.27)
					(thickness 0.15)
				)
				(justify left bottom)
				(hide yes)
			)
		)
		(property "Description" ""
			(at 326.39 83.82 0)
			(effects
				(font
					(size 1.27 1.27)
				)
				(hide yes)
			)
		)
		(property "Author" "Antmicro"
			(at 335.28 91.44 0)
			(effects
				(font
					(size 1.27 1.27)
					(thickness 0.15)
				)
				(justify left bottom)
				(hide yes)
			)
		)
		(property "License" "Apache-2.0"
			(at 335.28 93.98 0)
			(effects
				(font
					(size 1.27 1.27)
					(thickness 0.15)
				)
				(justify left bottom)
				(hide yes)
			)
		)
		(pin "1"
		)
		(instances
			(project "sdi-mipi-video-converter"
				(path ""
					(reference "#PWR0145")
					(unit 1)
				)
			)
		)
	)
	(symbol
		(lib_id "antmicropower:GND")
		(at 96.52 180.34 0)
		(unit 1)
		(exclude_from_sim no)
		(in_bom yes)
		(on_board yes)
		(dnp no)
		(fields_autoplaced yes)
		(property "Reference" "#PWR0111"
			(at 105.41 182.88 0)
			(effects
				(font
					(size 1.27 1.27)
					(thickness 0.15)
				)
				(justify left bottom)
				(hide yes)
			)
		)
		(property "Value" "GND"
			(at 96.52 185.42 0)
			(effects
				(font
					(size 1.27 1.27)
					(thickness 0.15)
				)
			)
		)
		(property "Footprint" ""
			(at 105.41 187.96 0)
			(effects
				(font
					(size 1.27 1.27)
					(thickness 0.15)
				)
				(justify left bottom)
				(hide yes)
			)
		)
		(property "Datasheet" ""
			(at 105.41 193.04 0)
			(effects
				(font
					(size 1.27 1.27)
					(thickness 0.15)
				)
				(justify left bottom)
				(hide yes)
			)
		)
		(property "Description" ""
			(at 96.52 180.34 0)
			(effects
				(font
					(size 1.27 1.27)
				)
				(hide yes)
			)
		)
		(property "Author" "Antmicro"
			(at 105.41 187.96 0)
			(effects
				(font
					(size 1.27 1.27)
					(thickness 0.15)
				)
				(justify left bottom)
				(hide yes)
			)
		)
		(property "License" "Apache-2.0"
			(at 105.41 190.5 0)
			(effects
				(font
					(size 1.27 1.27)
					(thickness 0.15)
				)
				(justify left bottom)
				(hide yes)
			)
		)
		(pin "1"
		)
		(instances
			(project "sdi-mipi-video-converter"
				(path ""
					(reference "#PWR0111")
					(unit 1)
				)
			)
		)
	)
	(symbol
		(lib_id "antmicropower:GND")
		(at 236.22 257.81 0)
		(unit 1)
		(exclude_from_sim no)
		(in_bom yes)
		(on_board yes)
		(dnp no)
		(fields_autoplaced yes)
		(property "Reference" "#PWR0120"
			(at 245.11 260.35 0)
			(effects
				(font
					(size 1.27 1.27)
					(thickness 0.15)
				)
				(justify left bottom)
				(hide yes)
			)
		)
		(property "Value" "GND"
			(at 236.22 262.89 0)
			(effects
				(font
					(size 1.27 1.27)
					(thickness 0.15)
				)
			)
		)
		(property "Footprint" ""
			(at 245.11 265.43 0)
			(effects
				(font
					(size 1.27 1.27)
					(thickness 0.15)
				)
				(justify left bottom)
				(hide yes)
			)
		)
		(property "Datasheet" ""
			(at 245.11 270.51 0)
			(effects
				(font
					(size 1.27 1.27)
					(thickness 0.15)
				)
				(justify left bottom)
				(hide yes)
			)
		)
		(property "Description" ""
			(at 236.22 257.81 0)
			(effects
				(font
					(size 1.27 1.27)
				)
				(hide yes)
			)
		)
		(property "Author" "Antmicro"
			(at 245.11 265.43 0)
			(effects
				(font
					(size 1.27 1.27)
					(thickness 0.15)
				)
				(justify left bottom)
				(hide yes)
			)
		)
		(property "License" "Apache-2.0"
			(at 245.11 267.97 0)
			(effects
				(font
					(size 1.27 1.27)
					(thickness 0.15)
				)
				(justify left bottom)
				(hide yes)
			)
		)
		(pin "1"
		)
		(instances
			(project "sdi-mipi-video-converter"
				(path ""
					(reference "#PWR0120")
					(unit 1)
				)
			)
		)
	)
	(symbol
		(lib_id "antmicropower:GND")
		(at 115.57 116.84 0)
		(unit 1)
		(exclude_from_sim no)
		(in_bom yes)
		(on_board yes)
		(dnp no)
		(fields_autoplaced yes)
		(property "Reference" "#PWR0115"
			(at 124.46 119.38 0)
			(effects
				(font
					(size 1.27 1.27)
					(thickness 0.15)
				)
				(justify left bottom)
				(hide yes)
			)
		)
		(property "Value" "GND"
			(at 115.57 121.92 0)
			(effects
				(font
					(size 1.27 1.27)
					(thickness 0.15)
				)
			)
		)
		(property "Footprint" ""
			(at 124.46 124.46 0)
			(effects
				(font
					(size 1.27 1.27)
					(thickness 0.15)
				)
				(justify left bottom)
				(hide yes)
			)
		)
		(property "Datasheet" ""
			(at 124.46 129.54 0)
			(effects
				(font
					(size 1.27 1.27)
					(thickness 0.15)
				)
				(justify left bottom)
				(hide yes)
			)
		)
		(property "Description" ""
			(at 115.57 116.84 0)
			(effects
				(font
					(size 1.27 1.27)
				)
				(hide yes)
			)
		)
		(property "Author" "Antmicro"
			(at 124.46 124.46 0)
			(effects
				(font
					(size 1.27 1.27)
					(thickness 0.15)
				)
				(justify left bottom)
				(hide yes)
			)
		)
		(property "License" "Apache-2.0"
			(at 124.46 127 0)
			(effects
				(font
					(size 1.27 1.27)
					(thickness 0.15)
				)
				(justify left bottom)
				(hide yes)
			)
		)
		(pin "1"
		)
		(instances
			(project "sdi-mipi-video-converter"
				(path ""
					(reference "#PWR0115")
					(unit 1)
				)
			)
		)
	)
	(symbol
		(lib_id "antmicroResistors0402:R_75R_0402")
		(at 328.93 69.85 0)
		(mirror x)
		(unit 1)
		(exclude_from_sim no)
		(in_bom yes)
		(on_board yes)
		(dnp no)
		(fields_autoplaced yes)
		(property "Reference" "R62"
			(at 331.47 63.5 0)
			(effects
				(font
					(size 1.27 1.27)
					(thickness 0.15)
				)
			)
		)
		(property "Value" "R_75R_0402"
			(at 349.25 57.15 0)
			(effects
				(font
					(size 1.27 1.27)
					(thickness 0.15)
				)
				(justify left bottom)
				(hide yes)
			)
		)
		(property "Footprint" "antmicro-footprints:R_0402_1005Metric"
			(at 349.25 54.61 0)
			(effects
				(font
					(size 1.27 1.27)
					(thickness 0.15)
				)
				(justify left bottom)
				(hide yes)
			)
		)
		(property "Datasheet" "https://www.bourns.com/docs/product-datasheets/cr.pdf"
			(at 349.25 52.07 0)
			(effects
				(font
					(size 1.27 1.27)
					(thickness 0.15)
				)
				(justify left bottom)
				(hide yes)
			)
		)
		(property "Description" "SMD Chip Resistor, 75 ohm, ± 1%, 62.5 mW, 0402 [1005 Metric], Thick Film, General Purpose"
			(at 328.93 69.85 0)
			(effects
				(font
					(size 1.27 1.27)
				)
				(hide yes)
			)
		)
		(property "Manufacturer" "Bourns"
			(at 349.25 46.99 0)
			(effects
				(font
					(size 1.27 1.27)
					(thickness 0.15)
				)
				(justify left bottom)
				(hide yes)
			)
		)
		(property "MPN" "CR0402-FX-75R0GLF"
			(at 349.25 49.53 0)
			(effects
				(font
					(size 1.27 1.27)
					(thickness 0.15)
				)
				(justify left bottom)
				(hide yes)
			)
		)
		(property "Val" "75R"
			(at 331.47 66.04 0)
			(effects
				(font
					(size 1.27 1.27)
					(thickness 0.15)
				)
			)
		)
		(property "License" "Apache-2.0"
			(at 349.25 44.45 0)
			(effects
				(font
					(size 1.27 1.27)
					(thickness 0.15)
				)
				(justify left bottom)
				(hide yes)
			)
		)
		(property "Author" "Antmicro"
			(at 349.25 41.91 0)
			(effects
				(font
					(size 1.27 1.27)
					(thickness 0.15)
				)
				(justify left bottom)
				(hide yes)
			)
		)
		(property "Tolerance" "1%"
			(at 349.25 59.69 0)
			(effects
				(font
					(size 1.27 1.27)
				)
				(justify left bottom)
				(hide yes)
			)
		)
		(pin "1"
		)
		(pin "2"
		)
		(instances
			(project "sdi-mipi-video-converter"
				(path ""
					(reference "R62")
					(unit 1)
				)
			)
		)
	)
	(symbol
		(lib_id "antmicroCapacitors0402:C_100n_0402")
		(at 270.51 217.17 90)
		(unit 1)
		(exclude_from_sim no)
		(in_bom yes)
		(on_board yes)
		(dnp no)
		(fields_autoplaced yes)
		(property "Reference" "C72"
			(at 267.97 213.3535 90)
			(effects
				(font
					(size 1.27 1.27)
					(thickness 0.15)
				)
				(justify left)
			)
		)
		(property "Value" "C_100n_0402"
			(at 280.67 196.85 0)
			(effects
				(font
					(size 1.27 1.27)
					(thickness 0.15)
				)
				(justify left bottom)
				(hide yes)
			)
		)
		(property "Footprint" "antmicro-footprints:C_0402_1005Metric"
			(at 283.21 196.85 0)
			(effects
				(font
					(size 1.27 1.27)
					(thickness 0.15)
				)
				(justify left bottom)
				(hide yes)
			)
		)
		(property "Datasheet" "https://www.murata.com/products/productdetail?partno=GRM155R61H104KE14%23"
			(at 285.75 196.85 0)
			(effects
				(font
					(size 1.27 1.27)
					(thickness 0.15)
				)
				(justify left bottom)
				(hide yes)
			)
		)
		(property "Description" "SMD Multilayer Ceramic Capacitor, 0.1 µF, 50 V, 0402 [1005 Metric], ± 10%, X5R, GRM Series"
			(at 270.51 217.17 0)
			(effects
				(font
					(size 1.27 1.27)
				)
				(hide yes)
			)
		)
		(property "Manufacturer" "Murata"
			(at 290.83 196.85 0)
			(effects
				(font
					(size 1.27 1.27)
					(thickness 0.15)
				)
				(justify left bottom)
				(hide yes)
			)
		)
		(property "MPN" "GRM155R61H104KE14D"
			(at 288.29 196.85 0)
			(effects
				(font
					(size 1.27 1.27)
					(thickness 0.15)
				)
				(justify left bottom)
				(hide yes)
			)
		)
		(property "Val" "100n"
			(at 267.97 215.8935 90)
			(effects
				(font
					(size 1.27 1.27)
					(thickness 0.15)
				)
				(justify left)
			)
		)
		(property "License" "Apache-2.0"
			(at 293.37 196.85 0)
			(effects
				(font
					(size 1.27 1.27)
					(thickness 0.15)
				)
				(justify left bottom)
				(hide yes)
			)
		)
		(property "Author" "Antmicro"
			(at 295.91 196.85 0)
			(effects
				(font
					(size 1.27 1.27)
					(thickness 0.15)
				)
				(justify left bottom)
				(hide yes)
			)
		)
		(property "Voltage" "50V"
			(at 298.45 196.85 0)
			(effects
				(font
					(size 1.27 1.27)
				)
				(justify left bottom)
				(hide yes)
			)
		)
		(property "Dielectric" "X5R"
			(at 300.99 196.85 0)
			(effects
				(font
					(size 1.27 1.27)
				)
				(justify left bottom)
				(hide yes)
			)
		)
		(pin "1"
		)
		(pin "2"
		)
		(instances
			(project "sdi-mipi-video-converter"
				(path ""
					(reference "C72")
					(unit 1)
				)
			)
		)
	)
	(symbol
		(lib_id "antmicroResistors0402:R_75R_0402")
		(at 53.34 199.39 0)
		(unit 1)
		(exclude_from_sim no)
		(in_bom yes)
		(on_board yes)
		(dnp no)
		(fields_autoplaced yes)
		(property "Reference" "R51"
			(at 55.88 203.2 0)
			(effects
				(font
					(size 1.27 1.27)
					(thickness 0.15)
				)
			)
		)
		(property "Value" "R_75R_0402"
			(at 73.66 212.09 0)
			(effects
				(font
					(size 1.27 1.27)
					(thickness 0.15)
				)
				(justify left bottom)
				(hide yes)
			)
		)
		(property "Footprint" "antmicro-footprints:R_0402_1005Metric"
			(at 73.66 214.63 0)
			(effects
				(font
					(size 1.27 1.27)
					(thickness 0.15)
				)
				(justify left bottom)
				(hide yes)
			)
		)
		(property "Datasheet" "https://www.bourns.com/docs/product-datasheets/cr.pdf"
			(at 73.66 217.17 0)
			(effects
				(font
					(size 1.27 1.27)
					(thickness 0.15)
				)
				(justify left bottom)
				(hide yes)
			)
		)
		(property "Description" "SMD Chip Resistor, 75 ohm, ± 1%, 62.5 mW, 0402 [1005 Metric], Thick Film, General Purpose"
			(at 53.34 199.39 0)
			(effects
				(font
					(size 1.27 1.27)
				)
				(hide yes)
			)
		)
		(property "Manufacturer" "Bourns"
			(at 73.66 222.25 0)
			(effects
				(font
					(size 1.27 1.27)
					(thickness 0.15)
				)
				(justify left bottom)
				(hide yes)
			)
		)
		(property "MPN" "CR0402-FX-75R0GLF"
			(at 73.66 219.71 0)
			(effects
				(font
					(size 1.27 1.27)
					(thickness 0.15)
				)
				(justify left bottom)
				(hide yes)
			)
		)
		(property "Val" "75R"
			(at 55.88 205.74 0)
			(effects
				(font
					(size 1.27 1.27)
					(thickness 0.15)
				)
			)
		)
		(property "License" "Apache-2.0"
			(at 73.66 224.79 0)
			(effects
				(font
					(size 1.27 1.27)
					(thickness 0.15)
				)
				(justify left bottom)
				(hide yes)
			)
		)
		(property "Author" "Antmicro"
			(at 73.66 227.33 0)
			(effects
				(font
					(size 1.27 1.27)
					(thickness 0.15)
				)
				(justify left bottom)
				(hide yes)
			)
		)
		(property "Tolerance" "1%"
			(at 73.66 209.55 0)
			(effects
				(font
					(size 1.27 1.27)
				)
				(justify left bottom)
				(hide yes)
			)
		)
		(pin "1"
		)
		(pin "2"
		)
		(instances
			(project "sdi-mipi-video-converter"
				(path ""
					(reference "R51")
					(unit 1)
				)
			)
		)
	)
	(symbol
		(lib_id "antmicropower:+3.3V")
		(at 212.09 59.69 0)
		(unit 1)
		(exclude_from_sim no)
		(in_bom yes)
		(on_board yes)
		(dnp no)
		(fields_autoplaced yes)
		(property "Reference" "#PWR0128"
			(at 212.09 63.5 0)
			(effects
				(font
					(size 1.27 1.27)
				)
				(hide yes)
			)
		)
		(property "Value" "+3V3"
			(at 212.09 54.61 0)
			(effects
				(font
					(size 1.27 1.27)
				)
			)
		)
		(property "Footprint" ""
			(at 212.09 59.69 0)
			(effects
				(font
					(size 1.27 1.27)
				)
				(hide yes)
			)
		)
		(property "Datasheet" ""
			(at 212.09 59.69 0)
			(effects
				(font
					(size 1.27 1.27)
				)
				(hide yes)
			)
		)
		(property "Description" ""
			(at 212.09 59.69 0)
			(effects
				(font
					(size 1.27 1.27)
				)
				(hide yes)
			)
		)
		(pin "1"
		)
		(instances
			(project "sdi-mipi-video-converter"
				(path ""
					(reference "#PWR0128")
					(unit 1)
				)
			)
		)
	)
	(symbol
		(lib_id "antmicropower:GND")
		(at 247.65 193.04 0)
		(unit 1)
		(exclude_from_sim no)
		(in_bom yes)
		(on_board yes)
		(dnp no)
		(fields_autoplaced yes)
		(property "Reference" "#PWR0122"
			(at 256.54 195.58 0)
			(effects
				(font
					(size 1.27 1.27)
					(thickness 0.15)
				)
				(justify left bottom)
				(hide yes)
			)
		)
		(property "Value" "GND"
			(at 247.65 198.12 0)
			(effects
				(font
					(size 1.27 1.27)
					(thickness 0.15)
				)
			)
		)
		(property "Footprint" ""
			(at 256.54 200.66 0)
			(effects
				(font
					(size 1.27 1.27)
					(thickness 0.15)
				)
				(justify left bottom)
				(hide yes)
			)
		)
		(property "Datasheet" ""
			(at 256.54 205.74 0)
			(effects
				(font
					(size 1.27 1.27)
					(thickness 0.15)
				)
				(justify left bottom)
				(hide yes)
			)
		)
		(property "Description" ""
			(at 247.65 193.04 0)
			(effects
				(font
					(size 1.27 1.27)
				)
				(hide yes)
			)
		)
		(property "Author" "Antmicro"
			(at 256.54 200.66 0)
			(effects
				(font
					(size 1.27 1.27)
					(thickness 0.15)
				)
				(justify left bottom)
				(hide yes)
			)
		)
		(property "License" "Apache-2.0"
			(at 256.54 203.2 0)
			(effects
				(font
					(size 1.27 1.27)
					(thickness 0.15)
				)
				(justify left bottom)
				(hide yes)
			)
		)
		(pin "1"
		)
		(instances
			(project "sdi-mipi-video-converter"
				(path ""
					(reference "#PWR0122")
					(unit 1)
				)
			)
		)
	)
	(symbol
		(lib_id "antmicroTestPoints:TP_0.75mm_SMD")
		(at 168.91 185.42 0)
		(unit 1)
		(exclude_from_sim no)
		(in_bom yes)
		(on_board yes)
		(dnp no)
		(fields_autoplaced yes)
		(property "Reference" "TP35"
			(at 173.99 185.4199 0)
			(effects
				(font
					(size 1.27 1.27)
					(thickness 0.15)
				)
				(justify left)
			)
		)
		(property "Value" "TP_0.75mm_SMD"
			(at 186.69 193.04 0)
			(effects
				(font
					(size 1.27 1.27)
					(thickness 0.15)
				)
				(justify left bottom)
				(hide yes)
			)
		)
		(property "Footprint" "antmicro-footprints:TP_SMD_0.75mm"
			(at 186.69 195.58 0)
			(effects
				(font
					(size 1.27 1.27)
					(thickness 0.15)
				)
				(justify left bottom)
				(hide yes)
			)
		)
		(property "Datasheet" ""
			(at 186.69 198.12 0)
			(effects
				(font
					(size 1.27 1.27)
					(thickness 0.15)
				)
				(justify left bottom)
				(hide yes)
			)
		)
		(property "Description" "SMT test point"
			(at 168.91 185.42 0)
			(effects
				(font
					(size 1.27 1.27)
				)
				(hide yes)
			)
		)
		(property "MPN" ""
			(at 186.69 200.66 0)
			(effects
				(font
					(size 1.27 1.27)
					(thickness 0.15)
				)
				(justify left bottom)
				(hide yes)
			)
		)
		(property "Manufacturer" ""
			(at 186.69 203.2 0)
			(effects
				(font
					(size 1.27 1.27)
					(thickness 0.15)
				)
				(justify left bottom)
				(hide yes)
			)
		)
		(property "Author" "Antmicro"
			(at 186.69 205.74 0)
			(effects
				(font
					(size 1.27 1.27)
					(thickness 0.15)
				)
				(justify left bottom)
				(hide yes)
			)
		)
		(property "License" "Apache-2.0"
			(at 186.69 208.28 0)
			(effects
				(font
					(size 1.27 1.27)
					(thickness 0.15)
				)
				(justify left bottom)
				(hide yes)
			)
		)
		(pin "1"
		)
		(instances
			(project "sdi-mipi-video-converter"
				(path ""
					(reference "TP35")
					(unit 1)
				)
			)
		)
	)
	(symbol
		(lib_id "antmicroTestPoints:TP_0.75mm_SMD")
		(at 168.91 195.58 0)
		(unit 1)
		(exclude_from_sim no)
		(in_bom yes)
		(on_board yes)
		(dnp no)
		(fields_autoplaced yes)
		(property "Reference" "TP39"
			(at 173.99 195.5799 0)
			(effects
				(font
					(size 1.27 1.27)
					(thickness 0.15)
				)
				(justify left)
			)
		)
		(property "Value" "TP_0.75mm_SMD"
			(at 186.69 203.2 0)
			(effects
				(font
					(size 1.27 1.27)
					(thickness 0.15)
				)
				(justify left bottom)
				(hide yes)
			)
		)
		(property "Footprint" "antmicro-footprints:TP_SMD_0.75mm"
			(at 186.69 205.74 0)
			(effects
				(font
					(size 1.27 1.27)
					(thickness 0.15)
				)
				(justify left bottom)
				(hide yes)
			)
		)
		(property "Datasheet" ""
			(at 186.69 208.28 0)
			(effects
				(font
					(size 1.27 1.27)
					(thickness 0.15)
				)
				(justify left bottom)
				(hide yes)
			)
		)
		(property "Description" "SMT test point"
			(at 168.91 195.58 0)
			(effects
				(font
					(size 1.27 1.27)
				)
				(hide yes)
			)
		)
		(property "MPN" ""
			(at 186.69 210.82 0)
			(effects
				(font
					(size 1.27 1.27)
					(thickness 0.15)
				)
				(justify left bottom)
				(hide yes)
			)
		)
		(property "Manufacturer" ""
			(at 186.69 213.36 0)
			(effects
				(font
					(size 1.27 1.27)
					(thickness 0.15)
				)
				(justify left bottom)
				(hide yes)
			)
		)
		(property "Author" "Antmicro"
			(at 186.69 215.9 0)
			(effects
				(font
					(size 1.27 1.27)
					(thickness 0.15)
				)
				(justify left bottom)
				(hide yes)
			)
		)
		(property "License" "Apache-2.0"
			(at 186.69 218.44 0)
			(effects
				(font
					(size 1.27 1.27)
					(thickness 0.15)
				)
				(justify left bottom)
				(hide yes)
			)
		)
		(pin "1"
		)
		(instances
			(project "sdi-mipi-video-converter"
				(path ""
					(reference "TP39")
					(unit 1)
				)
			)
		)
	)
	(symbol
		(lib_id "antmicroLEDIndicationDiscrete:LED_G_0603_LTST-C190GKT")
		(at 151.13 256.54 270)
		(mirror x)
		(unit 1)
		(exclude_from_sim no)
		(in_bom yes)
		(on_board yes)
		(dnp no)
		(property "Reference" "D7"
			(at 145.542 255.778 0)
			(effects
				(font
					(size 1.27 1.27)
					(thickness 0.15)
				)
				(justify left)
			)
		)
		(property "Value" "LED_G_0603_LTST-C190GKT"
			(at 147.828 271.526 0)
			(effects
				(font
					(size 1.27 1.27)
					(thickness 0.15)
				)
				(justify left)
			)
		)
		(property "Footprint" "antmicro-footprints:LED_0603_1608Metric_G"
			(at 140.97 233.68 0)
			(effects
				(font
					(size 1.27 1.27)
					(thickness 0.15)
				)
				(justify left bottom)
				(hide yes)
			)
		)
		(property "Datasheet" "https://media.digikey.com/pdf/Data%20Sheets/Lite-On%20PDFs/LTST-C190GKT.pdf"
			(at 138.43 233.68 0)
			(effects
				(font
					(size 1.27 1.27)
					(thickness 0.15)
				)
				(justify left bottom)
				(hide yes)
			)
		)
		(property "Description" "LED, Green, SMD, 0603, 20 mA, 2.1 V, 569 nm"
			(at 151.13 256.54 0)
			(effects
				(font
					(size 1.27 1.27)
				)
				(hide yes)
			)
		)
		(property "MPN" "LTST-C190GKT"
			(at 135.89 233.68 0)
			(effects
				(font
					(size 1.27 1.27)
					(thickness 0.15)
				)
				(justify left bottom)
				(hide yes)
			)
		)
		(property "Manufacturer" "Lite-On"
			(at 133.35 233.68 0)
			(effects
				(font
					(size 1.27 1.27)
					(thickness 0.15)
				)
				(justify left bottom)
				(hide yes)
			)
		)
		(property "Author" "Antmicro"
			(at 130.81 233.68 0)
			(effects
				(font
					(size 1.27 1.27)
					(thickness 0.15)
				)
				(justify left bottom)
				(hide yes)
			)
		)
		(property "License" "Apache-2.0"
			(at 128.27 233.68 0)
			(effects
				(font
					(size 1.27 1.27)
					(thickness 0.15)
				)
				(justify left bottom)
				(hide yes)
			)
		)
		(property "Color" "Green"
			(at 154.94 256.5399 90)
			(effects
				(font
					(size 1.27 1.27)
				)
				(justify left)
				(hide yes)
			)
		)
		(pin "1"
		)
		(pin "2"
		)
		(instances
			(project "sdi-mipi-video-converter"
				(path ""
					(reference "D7")
					(unit 1)
				)
			)
		)
	)
	(symbol
		(lib_id "antmicropower:+3.3V")
		(at 314.96 77.47 0)
		(unit 1)
		(exclude_from_sim no)
		(in_bom yes)
		(on_board yes)
		(dnp no)
		(fields_autoplaced yes)
		(property "Reference" "#PWR0144"
			(at 314.96 81.28 0)
			(effects
				(font
					(size 1.27 1.27)
				)
				(hide yes)
			)
		)
		(property "Value" "+3V3"
			(at 314.96 72.39 0)
			(effects
				(font
					(size 1.27 1.27)
				)
			)
		)
		(property "Footprint" ""
			(at 314.96 77.47 0)
			(effects
				(font
					(size 1.27 1.27)
				)
				(hide yes)
			)
		)
		(property "Datasheet" ""
			(at 314.96 77.47 0)
			(effects
				(font
					(size 1.27 1.27)
				)
				(hide yes)
			)
		)
		(property "Description" ""
			(at 314.96 77.47 0)
			(effects
				(font
					(size 1.27 1.27)
				)
				(hide yes)
			)
		)
		(pin "1"
		)
		(instances
			(project "sdi-mipi-video-converter"
				(path ""
					(reference "#PWR0144")
					(unit 1)
				)
			)
		)
	)
	(symbol
		(lib_id "antmicroFPGAChips:CrossLink_LIFCL-40-9BG256C")
		(at 180.34 63.5 0)
		(mirror y)
		(unit 3)
		(exclude_from_sim no)
		(in_bom yes)
		(on_board yes)
		(dnp no)
		(fields_autoplaced yes)
		(property "Reference" "U11"
			(at 157.48 55.88 0)
			(effects
				(font
					(size 1.27 1.27)
					(thickness 0.15)
				)
			)
		)
		(property "Value" "LIFCL-40-9BG256C"
			(at 157.48 55.88 0)
			(effects
				(font
					(size 1.27 1.27)
					(thickness 0.15)
				)
				(hide yes)
			)
		)
		(property "Footprint" "antmicro-footprints:BGA-256_14x14mm_Layout16x16_P0.8mm"
			(at 127 71.12 0)
			(effects
				(font
					(size 1.27 1.27)
					(thickness 0.15)
				)
				(justify left bottom)
				(hide yes)
			)
		)
		(property "Datasheet" "https://www.latticesemi.com/-/media/LatticeSemi/Documents/DataSheets/CrossLink/FPGA-DS-02007-2-1-CrossLink-Family-Data-Sheet.ashx?document_id=51662"
			(at 127 73.66 0)
			(effects
				(font
					(size 1.27 1.27)
					(thickness 0.15)
				)
				(justify left bottom)
				(hide yes)
			)
		)
		(property "Description" "CrossLink-NX™ Field Programmable Gate Array 256-LFBGA"
			(at 180.34 63.5 0)
			(effects
				(font
					(size 1.27 1.27)
				)
				(hide yes)
			)
		)
		(property "MPN" "LIFCL-40-9BG256C"
			(at 157.48 58.42 0)
			(effects
				(font
					(size 1.27 1.27)
					(thickness 0.15)
				)
			)
		)
		(property "Manufacturer" "Lattice Semiconductor"
			(at 127 76.2 0)
			(effects
				(font
					(size 1.27 1.27)
					(thickness 0.15)
				)
				(justify left bottom)
				(hide yes)
			)
		)
		(property "Author" "Antmicro"
			(at 127 78.74 0)
			(effects
				(font
					(size 1.27 1.27)
					(thickness 0.15)
				)
				(justify left bottom)
				(hide yes)
			)
		)
		(property "License" "Apache-2.0"
			(at 127 81.28 0)
			(effects
				(font
					(size 1.27 1.27)
					(thickness 0.15)
				)
				(justify left bottom)
				(hide yes)
			)
		)
		(pin "B16"
		)
		(pin "C12"
		)
		(pin "C13"
		)
		(pin "C14"
		)
		(pin "C15"
		)
		(pin "C16"
		)
		(pin "D11"
		)
		(pin "D12"
		)
		(pin "D13"
		)
		(pin "D15"
		)
		(pin "D16"
		)
		(pin "E15"
		)
		(pin "E16"
		)
		(pin "D10"
		)
		(pin "E10"
		)
		(pin "E11"
		)
		(pin "E12"
		)
		(pin "E13"
		)
		(pin "E14"
		)
		(pin "E9"
		)
		(pin "F10"
		)
		(pin "F11"
		)
		(pin "F13"
		)
		(pin "F14"
		)
		(pin "F15"
		)
		(pin "F16"
		)
		(pin "F9"
		)
		(pin "G10"
		)
		(pin "G11"
		)
		(pin "G12"
		)
		(pin "G13"
		)
		(pin "G14"
		)
		(pin "G15"
		)
		(pin "G16"
		)
		(pin "G9"
		)
		(pin "H10"
		)
		(pin "H11"
		)
		(pin "H12"
		)
		(pin "H13"
		)
		(pin "H14"
		)
		(pin "H15"
		)
		(pin "H16"
		)
		(pin "J11"
		)
		(pin "J12"
		)
		(pin "J13"
		)
		(pin "J15"
		)
		(pin "J16"
		)
		(pin "K11"
		)
		(pin "K12"
		)
		(pin "L10"
		)
		(pin "L11"
		)
		(pin "L12"
		)
		(pin "M11"
		)
		(pin "M12"
		)
		(pin "M13"
		)
		(pin "M14"
		)
		(pin "M15"
		)
		(pin "M16"
		)
		(pin "N11"
		)
		(pin "N12"
		)
		(pin "N13"
		)
		(pin "N14"
		)
		(pin "N15"
		)
		(pin "N16"
		)
		(pin "P10"
		)
		(pin "P11"
		)
		(pin "P12"
		)
		(pin "P14"
		)
		(pin "P15"
		)
		(pin "P16"
		)
		(pin "R10"
		)
		(pin "R11"
		)
		(pin "R12"
		)
		(pin "R13"
		)
		(pin "R14"
		)
		(pin "R15"
		)
		(pin "R16"
		)
		(pin "T11"
		)
		(pin "T12"
		)
		(pin "T13"
		)
		(pin "T14"
		)
		(pin "T15"
		)
		(pin "L8"
		)
		(pin "L9"
		)
		(pin "M10"
		)
		(pin "M8"
		)
		(pin "M9"
		)
		(pin "N10"
		)
		(pin "N6"
		)
		(pin "N8"
		)
		(pin "N9"
		)
		(pin "P4"
		)
		(pin "P5"
		)
		(pin "P6"
		)
		(pin "P7"
		)
		(pin "P8"
		)
		(pin "P9"
		)
		(pin "R1"
		)
		(pin "R2"
		)
		(pin "R3"
		)
		(pin "R4"
		)
		(pin "R5"
		)
		(pin "R6"
		)
		(pin "R7"
		)
		(pin "R8"
		)
		(pin "R9"
		)
		(pin "T10"
		)
		(pin "T2"
		)
		(pin "T3"
		)
		(pin "T4"
		)
		(pin "T5"
		)
		(pin "T6"
		)
		(pin "T7"
		)
		(pin "T8"
		)
		(pin "T9"
		)
		(pin "K7"
		)
		(pin "L6"
		)
		(pin "L7"
		)
		(pin "M4"
		)
		(pin "M7"
		)
		(pin "N3"
		)
		(pin "N4"
		)
		(pin "N5"
		)
		(pin "P1"
		)
		(pin "P2"
		)
		(pin "P3"
		)
		(pin "H1"
		)
		(pin "H2"
		)
		(pin "H3"
		)
		(pin "H4"
		)
		(pin "H5"
		)
		(pin "H6"
		)
		(pin "J1"
		)
		(pin "J2"
		)
		(pin "J4"
		)
		(pin "J5"
		)
		(pin "J6"
		)
		(pin "K1"
		)
		(pin "K2"
		)
		(pin "K3"
		)
		(pin "K4"
		)
		(pin "K5"
		)
		(pin "K6"
		)
		(pin "L1"
		)
		(pin "L2"
		)
		(pin "L3"
		)
		(pin "L4"
		)
		(pin "L5"
		)
		(pin "M1"
		)
		(pin "M2"
		)
		(pin "M3"
		)
		(pin "N1"
		)
		(pin "N2"
		)
		(pin "D4"
		)
		(pin "D5"
		)
		(pin "D6"
		)
		(pin "E4"
		)
		(pin "E5"
		)
		(pin "E6"
		)
		(pin "F4"
		)
		(pin "F5"
		)
		(pin "F6"
		)
		(pin "G3"
		)
		(pin "G4"
		)
		(pin "G6"
		)
		(pin "B1"
		)
		(pin "B2"
		)
		(pin "C1"
		)
		(pin "C2"
		)
		(pin "D1"
		)
		(pin "D2"
		)
		(pin "E1"
		)
		(pin "E2"
		)
		(pin "F1"
		)
		(pin "F2"
		)
		(pin "A3"
		)
		(pin "A4"
		)
		(pin "A5"
		)
		(pin "A6"
		)
		(pin "A7"
		)
		(pin "B3"
		)
		(pin "B4"
		)
		(pin "B5"
		)
		(pin "B6"
		)
		(pin "B7"
		)
		(pin "K13"
		)
		(pin "K14"
		)
		(pin "K15"
		)
		(pin "K16"
		)
		(pin "L13"
		)
		(pin "L14"
		)
		(pin "L15"
		)
		(pin "L16"
		)
		(pin "A11"
		)
		(pin "A12"
		)
		(pin "A14"
		)
		(pin "A15"
		)
		(pin "A9"
		)
		(pin "B12"
		)
		(pin "B9"
		)
		(pin "C11"
		)
		(pin "A1"
		)
		(pin "A10"
		)
		(pin "A13"
		)
		(pin "A16"
		)
		(pin "A2"
		)
		(pin "A8"
		)
		(pin "B10"
		)
		(pin "B11"
		)
		(pin "B13"
		)
		(pin "B14"
		)
		(pin "B15"
		)
		(pin "B8"
		)
		(pin "C10"
		)
		(pin "C3"
		)
		(pin "C4"
		)
		(pin "C5"
		)
		(pin "C6"
		)
		(pin "C7"
		)
		(pin "C8"
		)
		(pin "C9"
		)
		(pin "D14"
		)
		(pin "D3"
		)
		(pin "D7"
		)
		(pin "D8"
		)
		(pin "D9"
		)
		(pin "E3"
		)
		(pin "E7"
		)
		(pin "E8"
		)
		(pin "F12"
		)
		(pin "F3"
		)
		(pin "F7"
		)
		(pin "F8"
		)
		(pin "G1"
		)
		(pin "G2"
		)
		(pin "G5"
		)
		(pin "G7"
		)
		(pin "G8"
		)
		(pin "H7"
		)
		(pin "H8"
		)
		(pin "H9"
		)
		(pin "J10"
		)
		(pin "J14"
		)
		(pin "J3"
		)
		(pin "J7"
		)
		(pin "J8"
		)
		(pin "J9"
		)
		(pin "K10"
		)
		(pin "K8"
		)
		(pin "K9"
		)
		(pin "M5"
		)
		(pin "M6"
		)
		(pin "N7"
		)
		(pin "P13"
		)
		(pin "T1"
		)
		(pin "T16"
		)
		(instances
			(project "sdi-mipi-video-converter"
				(path ""
					(reference "U11")
					(unit 3)
				)
			)
		)
	)
	(symbol
		(lib_id "antmicroCapacitors0402:C_100n_0402")
		(at 270.51 191.77 90)
		(unit 1)
		(exclude_from_sim no)
		(in_bom yes)
		(on_board yes)
		(dnp no)
		(fields_autoplaced yes)
		(property "Reference" "C70"
			(at 273.05 187.9535 90)
			(effects
				(font
					(size 1.27 1.27)
					(thickness 0.15)
				)
				(justify right)
			)
		)
		(property "Value" "C_100n_0402"
			(at 280.67 171.45 0)
			(effects
				(font
					(size 1.27 1.27)
					(thickness 0.15)
				)
				(justify left bottom)
				(hide yes)
			)
		)
		(property "Footprint" "antmicro-footprints:C_0402_1005Metric"
			(at 283.21 171.45 0)
			(effects
				(font
					(size 1.27 1.27)
					(thickness 0.15)
				)
				(justify left bottom)
				(hide yes)
			)
		)
		(property "Datasheet" "https://www.murata.com/products/productdetail?partno=GRM155R61H104KE14%23"
			(at 285.75 171.45 0)
			(effects
				(font
					(size 1.27 1.27)
					(thickness 0.15)
				)
				(justify left bottom)
				(hide yes)
			)
		)
		(property "Description" "SMD Multilayer Ceramic Capacitor, 0.1 µF, 50 V, 0402 [1005 Metric], ± 10%, X5R, GRM Series"
			(at 270.51 191.77 0)
			(effects
				(font
					(size 1.27 1.27)
				)
				(hide yes)
			)
		)
		(property "Manufacturer" "Murata"
			(at 290.83 171.45 0)
			(effects
				(font
					(size 1.27 1.27)
					(thickness 0.15)
				)
				(justify left bottom)
				(hide yes)
			)
		)
		(property "MPN" "GRM155R61H104KE14D"
			(at 288.29 171.45 0)
			(effects
				(font
					(size 1.27 1.27)
					(thickness 0.15)
				)
				(justify left bottom)
				(hide yes)
			)
		)
		(property "Val" "100n"
			(at 273.05 190.4935 90)
			(effects
				(font
					(size 1.27 1.27)
					(thickness 0.15)
				)
				(justify right)
			)
		)
		(property "License" "Apache-2.0"
			(at 293.37 171.45 0)
			(effects
				(font
					(size 1.27 1.27)
					(thickness 0.15)
				)
				(justify left bottom)
				(hide yes)
			)
		)
		(property "Author" "Antmicro"
			(at 295.91 171.45 0)
			(effects
				(font
					(size 1.27 1.27)
					(thickness 0.15)
				)
				(justify left bottom)
				(hide yes)
			)
		)
		(property "Voltage" "50V"
			(at 298.45 171.45 0)
			(effects
				(font
					(size 1.27 1.27)
				)
				(justify left bottom)
				(hide yes)
			)
		)
		(property "Dielectric" "X5R"
			(at 300.99 171.45 0)
			(effects
				(font
					(size 1.27 1.27)
				)
				(justify left bottom)
				(hide yes)
			)
		)
		(pin "1"
		)
		(pin "2"
		)
		(instances
			(project "sdi-mipi-video-converter"
				(path ""
					(reference "C70")
					(unit 1)
				)
			)
		)
	)
	(symbol
		(lib_id "antmicropower:GND")
		(at 55.88 184.15 0)
		(unit 1)
		(exclude_from_sim no)
		(in_bom yes)
		(on_board yes)
		(dnp no)
		(property "Reference" "#PWR0107"
			(at 64.77 186.69 0)
			(effects
				(font
					(size 1.27 1.27)
					(thickness 0.15)
				)
				(justify left bottom)
				(hide yes)
			)
		)
		(property "Value" "GND"
			(at 57.785 187.96 0)
			(effects
				(font
					(size 1.27 1.27)
					(thickness 0.15)
				)
				(justify right)
			)
		)
		(property "Footprint" ""
			(at 64.77 191.77 0)
			(effects
				(font
					(size 1.27 1.27)
					(thickness 0.15)
				)
				(justify left bottom)
				(hide yes)
			)
		)
		(property "Datasheet" ""
			(at 64.77 196.85 0)
			(effects
				(font
					(size 1.27 1.27)
					(thickness 0.15)
				)
				(justify left bottom)
				(hide yes)
			)
		)
		(property "Description" ""
			(at 55.88 184.15 0)
			(effects
				(font
					(size 1.27 1.27)
				)
				(hide yes)
			)
		)
		(property "Author" "Antmicro"
			(at 64.77 191.77 0)
			(effects
				(font
					(size 1.27 1.27)
					(thickness 0.15)
				)
				(justify left bottom)
				(hide yes)
			)
		)
		(property "License" "Apache-2.0"
			(at 64.77 194.31 0)
			(effects
				(font
					(size 1.27 1.27)
					(thickness 0.15)
				)
				(justify left bottom)
				(hide yes)
			)
		)
		(pin "1"
		)
		(instances
			(project "sdi-mipi-video-converter"
				(path ""
					(reference "#PWR0107")
					(unit 1)
				)
			)
		)
	)
	(symbol
		(lib_id "antmicroCapacitors0402:C_33p_0402")
		(at 59.69 182.88 0)
		(unit 1)
		(exclude_from_sim no)
		(in_bom yes)
		(on_board yes)
		(dnp no)
		(property "Reference" "C52"
			(at 62.23 186.055 0)
			(effects
				(font
					(size 1.27 1.27)
					(thickness 0.15)
				)
			)
		)
		(property "Value" "C_33p_0402"
			(at 80.01 193.04 0)
			(effects
				(font
					(size 1.27 1.27)
					(thickness 0.15)
				)
				(justify left bottom)
				(hide yes)
			)
		)
		(property "Footprint" "antmicro-footprints:C_0402_1005Metric"
			(at 80.01 195.58 0)
			(effects
				(font
					(size 1.27 1.27)
					(thickness 0.15)
				)
				(justify left bottom)
				(hide yes)
			)
		)
		(property "Datasheet" "https://spicat.kyocera-avx.com/product/mlcc/chartview/04025A330FAT2A/"
			(at 80.01 198.12 0)
			(effects
				(font
					(size 1.27 1.27)
					(thickness 0.15)
				)
				(justify left bottom)
				(hide yes)
			)
		)
		(property "Description" "SMD Multilayer Ceramic Capacitor, 33 pF, 50 V, 0402 [1005 Metric], ± 5%, C0G / NP0, MC"
			(at 59.69 182.88 0)
			(effects
				(font
					(size 1.27 1.27)
				)
				(hide yes)
			)
		)
		(property "Manufacturer" "KYOCERA AVX"
			(at 80.01 203.2 0)
			(effects
				(font
					(size 1.27 1.27)
					(thickness 0.15)
				)
				(justify left bottom)
				(hide yes)
			)
		)
		(property "MPN" "04025A330FAT2A"
			(at 80.01 200.66 0)
			(effects
				(font
					(size 1.27 1.27)
					(thickness 0.15)
				)
				(justify left bottom)
				(hide yes)
			)
		)
		(property "Val" "33p"
			(at 62.23 188.595 0)
			(effects
				(font
					(size 1.27 1.27)
					(thickness 0.15)
				)
			)
		)
		(property "License" "Apache-2.0"
			(at 80.01 205.74 0)
			(effects
				(font
					(size 1.27 1.27)
					(thickness 0.15)
				)
				(justify left bottom)
				(hide yes)
			)
		)
		(property "Author" "Antmicro"
			(at 80.01 208.28 0)
			(effects
				(font
					(size 1.27 1.27)
					(thickness 0.15)
				)
				(justify left bottom)
				(hide yes)
			)
		)
		(property "Voltage" ""
			(at 80.01 210.82 0)
			(effects
				(font
					(size 1.27 1.27)
				)
				(justify left bottom)
				(hide yes)
			)
		)
		(property "Dielectric" ""
			(at 80.01 213.36 0)
			(effects
				(font
					(size 1.27 1.27)
				)
				(justify left bottom)
				(hide yes)
			)
		)
		(pin "1"
		)
		(pin "2"
		)
		(instances
			(project "sdi-mipi-video-converter"
				(path ""
					(reference "C52")
					(unit 1)
				)
			)
		)
	)
	(symbol
		(lib_id "antmicroResistors0402:R_75R_0402")
		(at 309.88 86.36 0)
		(mirror y)
		(unit 1)
		(exclude_from_sim no)
		(in_bom yes)
		(on_board yes)
		(dnp no)
		(property "Reference" "R59"
			(at 311.785 85.09 0)
			(effects
				(font
					(size 1.27 1.27)
					(thickness 0.15)
				)
			)
		)
		(property "Value" "R_75R_0402"
			(at 289.56 99.06 0)
			(effects
				(font
					(size 1.27 1.27)
					(thickness 0.15)
				)
				(justify left bottom)
				(hide yes)
			)
		)
		(property "Footprint" "antmicro-footprints:R_0402_1005Metric"
			(at 289.56 101.6 0)
			(effects
				(font
					(size 1.27 1.27)
					(thickness 0.15)
				)
				(justify left bottom)
				(hide yes)
			)
		)
		(property "Datasheet" "https://www.bourns.com/docs/product-datasheets/cr.pdf"
			(at 289.56 104.14 0)
			(effects
				(font
					(size 1.27 1.27)
					(thickness 0.15)
				)
				(justify left bottom)
				(hide yes)
			)
		)
		(property "Description" "SMD Chip Resistor, 75 ohm, ± 1%, 62.5 mW, 0402 [1005 Metric], Thick Film, General Purpose"
			(at 309.88 86.36 0)
			(effects
				(font
					(size 1.27 1.27)
				)
				(hide yes)
			)
		)
		(property "Manufacturer" "Bourns"
			(at 289.56 109.22 0)
			(effects
				(font
					(size 1.27 1.27)
					(thickness 0.15)
				)
				(justify left bottom)
				(hide yes)
			)
		)
		(property "MPN" "CR0402-FX-75R0GLF"
			(at 289.56 106.68 0)
			(effects
				(font
					(size 1.27 1.27)
					(thickness 0.15)
				)
				(justify left bottom)
				(hide yes)
			)
		)
		(property "Val" "75R"
			(at 302.895 85.09 0)
			(effects
				(font
					(size 1.27 1.27)
					(thickness 0.15)
				)
			)
		)
		(property "License" "Apache-2.0"
			(at 289.56 111.76 0)
			(effects
				(font
					(size 1.27 1.27)
					(thickness 0.15)
				)
				(justify left bottom)
				(hide yes)
			)
		)
		(property "Author" "Antmicro"
			(at 289.56 114.3 0)
			(effects
				(font
					(size 1.27 1.27)
					(thickness 0.15)
				)
				(justify left bottom)
				(hide yes)
			)
		)
		(property "Tolerance" "1%"
			(at 289.56 96.52 0)
			(effects
				(font
					(size 1.27 1.27)
				)
				(justify left bottom)
				(hide yes)
			)
		)
		(pin "1"
		)
		(pin "2"
		)
		(instances
			(project "sdi-mipi-video-converter"
				(path ""
					(reference "R59")
					(unit 1)
				)
			)
		)
	)
	(symbol
		(lib_id "antmicroFixedInductors:L_6n2_0.7A_0402")
		(at 58.42 194.31 0)
		(mirror y)
		(unit 1)
		(exclude_from_sim no)
		(in_bom yes)
		(on_board yes)
		(dnp no)
		(property "Reference" "L4"
			(at 53.34 192.405 0)
			(effects
				(font
					(size 1.27 1.27)
					(thickness 0.15)
				)
			)
		)
		(property "Value" "L_6n2_0.7A_0402"
			(at 44.45 196.85 0)
			(effects
				(font
					(size 1.27 1.27)
					(thickness 0.15)
				)
				(justify left bottom)
				(hide yes)
			)
		)
		(property "Footprint" "antmicro-footprints:L_0402_1005Metric"
			(at 44.45 201.93 0)
			(effects
				(font
					(size 1.27 1.27)
					(thickness 0.15)
				)
				(justify left bottom)
				(hide yes)
			)
		)
		(property "Datasheet" "https://www.mouser.com/datasheet/2/281/1/JELF243A_0050-1380872.pdf"
			(at 44.45 204.47 0)
			(effects
				(font
					(size 1.27 1.27)
					(thickness 0.15)
				)
				(justify left bottom)
				(hide yes)
			)
		)
		(property "Description" "Wirewound Inductor, 6.2 nH, 0.09 ohm, 8 GHz, 700 mA, 0402 [1005 Metric], LQW"
			(at 58.42 194.31 0)
			(effects
				(font
					(size 1.27 1.27)
				)
				(hide yes)
			)
		)
		(property "MPN" "LQW15AN6N2C00D"
			(at 44.45 209.55 0)
			(effects
				(font
					(size 1.27 1.27)
					(thickness 0.15)
				)
				(justify left bottom)
				(hide yes)
			)
		)
		(property "Manufacturer" "Murata"
			(at 44.45 207.01 0)
			(effects
				(font
					(size 1.27 1.27)
					(thickness 0.15)
				)
				(justify left bottom)
				(hide yes)
			)
		)
		(property "Val" "6n2/0.7A"
			(at 59.055 192.405 0)
			(effects
				(font
					(size 1.27 1.27)
					(thickness 0.15)
				)
			)
		)
		(property "ISat" ""
			(at 44.45 210.82 0)
			(effects
				(font
					(size 1.27 1.27)
				)
				(justify left)
				(hide yes)
			)
		)
		(property "IMax" "0.7 A"
			(at 44.45 214.63 0)
			(effects
				(font
					(size 1.27 1.27)
					(thickness 0.15)
				)
				(justify left bottom)
				(hide yes)
			)
		)
		(property "Size" "1.0x0.5"
			(at 44.45 217.17 0)
			(effects
				(font
					(size 1.27 1.27)
					(thickness 0.15)
				)
				(justify left bottom)
				(hide yes)
			)
		)
		(property "Author" "Antmicro"
			(at 44.45 219.71 0)
			(effects
				(font
					(size 1.27 1.27)
					(thickness 0.15)
				)
				(justify left bottom)
				(hide yes)
			)
		)
		(property "License" "Apache-2.0"
			(at 44.45 222.25 0)
			(effects
				(font
					(size 1.27 1.27)
					(thickness 0.15)
				)
				(justify left bottom)
				(hide yes)
			)
		)
		(pin "1"
		)
		(pin "2"
		)
		(instances
			(project "sdi-mipi-video-converter"
				(path ""
					(reference "L4")
					(unit 1)
				)
			)
		)
	)
	(symbol
		(lib_id "antmicropower:GND")
		(at 212.09 73.66 0)
		(unit 1)
		(exclude_from_sim no)
		(in_bom yes)
		(on_board yes)
		(dnp no)
		(fields_autoplaced yes)
		(property "Reference" "#PWR0129"
			(at 220.98 76.2 0)
			(effects
				(font
					(size 1.27 1.27)
					(thickness 0.15)
				)
				(justify left bottom)
				(hide yes)
			)
		)
		(property "Value" "GND"
			(at 212.09 78.74 0)
			(effects
				(font
					(size 1.27 1.27)
					(thickness 0.15)
				)
			)
		)
		(property "Footprint" ""
			(at 220.98 81.28 0)
			(effects
				(font
					(size 1.27 1.27)
					(thickness 0.15)
				)
				(justify left bottom)
				(hide yes)
			)
		)
		(property "Datasheet" ""
			(at 220.98 86.36 0)
			(effects
				(font
					(size 1.27 1.27)
					(thickness 0.15)
				)
				(justify left bottom)
				(hide yes)
			)
		)
		(property "Description" ""
			(at 212.09 73.66 0)
			(effects
				(font
					(size 1.27 1.27)
				)
				(hide yes)
			)
		)
		(property "Author" "Antmicro"
			(at 220.98 81.28 0)
			(effects
				(font
					(size 1.27 1.27)
					(thickness 0.15)
				)
				(justify left bottom)
				(hide yes)
			)
		)
		(property "License" "Apache-2.0"
			(at 220.98 83.82 0)
			(effects
				(font
					(size 1.27 1.27)
					(thickness 0.15)
				)
				(justify left bottom)
				(hide yes)
			)
		)
		(pin "1"
		)
		(instances
			(project "sdi-mipi-video-converter"
				(path ""
					(reference "#PWR0129")
					(unit 1)
				)
			)
		)
	)
	(symbol
		(lib_id "antmicroCapacitorsmisc:C_100n_0201")
		(at 115.57 115.57 90)
		(unit 1)
		(exclude_from_sim no)
		(in_bom yes)
		(on_board yes)
		(dnp no)
		(fields_autoplaced yes)
		(property "Reference" "C58"
			(at 118.11 111.7535 90)
			(effects
				(font
					(size 1.27 1.27)
					(thickness 0.15)
				)
				(justify right)
			)
		)
		(property "Value" "C_100n_0201"
			(at 125.73 95.25 0)
			(effects
				(font
					(size 1.27 1.27)
					(thickness 0.15)
				)
				(justify left bottom)
				(hide yes)
			)
		)
		(property "Footprint" "antmicro-footprints:C_0201"
			(at 128.27 95.25 0)
			(effects
				(font
					(size 1.27 1.27)
					(thickness 0.15)
				)
				(justify left bottom)
				(hide yes)
			)
		)
		(property "Datasheet" "https://www.yageo.com/en/Chart/Download/pdf/CC0201KRX6S5BB104"
			(at 130.81 95.25 0)
			(effects
				(font
					(size 1.27 1.27)
					(thickness 0.15)
				)
				(justify left bottom)
				(hide yes)
			)
		)
		(property "Description" "SMD Multilayer Ceramic Capacitor, 0.1 µF, 6.3 V, 0201 [0603 Metric], ± 10%, X6S, CC Series"
			(at 115.57 115.57 0)
			(effects
				(font
					(size 1.27 1.27)
				)
				(hide yes)
			)
		)
		(property "Manufacturer" "YAGEO"
			(at 135.89 95.25 0)
			(effects
				(font
					(size 1.27 1.27)
					(thickness 0.15)
				)
				(justify left bottom)
				(hide yes)
			)
		)
		(property "MPN" "CC0201KRX6S5BB104"
			(at 133.35 95.25 0)
			(effects
				(font
					(size 1.27 1.27)
					(thickness 0.15)
				)
				(justify left bottom)
				(hide yes)
			)
		)
		(property "Val" "100n"
			(at 118.11 114.2935 90)
			(effects
				(font
					(size 1.27 1.27)
					(thickness 0.15)
				)
				(justify right)
			)
		)
		(property "License" "Apache-2.0"
			(at 138.43 95.25 0)
			(effects
				(font
					(size 1.27 1.27)
					(thickness 0.15)
				)
				(justify left bottom)
				(hide yes)
			)
		)
		(property "Author" "Antmicro"
			(at 140.97 95.25 0)
			(effects
				(font
					(size 1.27 1.27)
					(thickness 0.15)
				)
				(justify left bottom)
				(hide yes)
			)
		)
		(property "Voltage" ""
			(at 143.51 95.25 0)
			(effects
				(font
					(size 1.27 1.27)
				)
				(justify left bottom)
				(hide yes)
			)
		)
		(property "Dielectric" ""
			(at 146.05 95.25 0)
			(effects
				(font
					(size 1.27 1.27)
				)
				(justify left bottom)
				(hide yes)
			)
		)
		(property "Public" "False"
			(at 148.59 95.25 0)
			(effects
				(font
					(size 1.27 1.27)
				)
				(justify left bottom)
				(hide yes)
			)
		)
		(pin "1"
		)
		(pin "2"
		)
		(instances
			(project "sdi-mipi-video-converter"
				(path ""
					(reference "C58")
					(unit 1)
				)
			)
		)
	)
	(symbol
		(lib_id "antmicroTestPoints:TP_0.75mm_SMD")
		(at 132.08 232.41 0)
		(unit 1)
		(exclude_from_sim no)
		(in_bom yes)
		(on_board yes)
		(dnp no)
		(fields_autoplaced yes)
		(property "Reference" "TP25"
			(at 137.16 232.4099 0)
			(effects
				(font
					(size 1.27 1.27)
					(thickness 0.15)
				)
				(justify left)
			)
		)
		(property "Value" "TP_0.75mm_SMD"
			(at 149.86 240.03 0)
			(effects
				(font
					(size 1.27 1.27)
					(thickness 0.15)
				)
				(justify left bottom)
				(hide yes)
			)
		)
		(property "Footprint" "antmicro-footprints:TP_SMD_0.75mm"
			(at 149.86 242.57 0)
			(effects
				(font
					(size 1.27 1.27)
					(thickness 0.15)
				)
				(justify left bottom)
				(hide yes)
			)
		)
		(property "Datasheet" ""
			(at 149.86 245.11 0)
			(effects
				(font
					(size 1.27 1.27)
					(thickness 0.15)
				)
				(justify left bottom)
				(hide yes)
			)
		)
		(property "Description" "SMT test point"
			(at 132.08 232.41 0)
			(effects
				(font
					(size 1.27 1.27)
				)
				(hide yes)
			)
		)
		(property "MPN" ""
			(at 149.86 247.65 0)
			(effects
				(font
					(size 1.27 1.27)
					(thickness 0.15)
				)
				(justify left bottom)
				(hide yes)
			)
		)
		(property "Manufacturer" ""
			(at 149.86 250.19 0)
			(effects
				(font
					(size 1.27 1.27)
					(thickness 0.15)
				)
				(justify left bottom)
				(hide yes)
			)
		)
		(property "Author" "Antmicro"
			(at 149.86 252.73 0)
			(effects
				(font
					(size 1.27 1.27)
					(thickness 0.15)
				)
				(justify left bottom)
				(hide yes)
			)
		)
		(property "License" "Apache-2.0"
			(at 149.86 255.27 0)
			(effects
				(font
					(size 1.27 1.27)
					(thickness 0.15)
				)
				(justify left bottom)
				(hide yes)
			)
		)
		(pin "1"
		)
		(instances
			(project "sdi-mipi-video-converter"
				(path ""
					(reference "TP25")
					(unit 1)
				)
			)
		)
	)
	(symbol
		(lib_id "antmicropower:+1V2")
		(at 266.7 160.02 0)
		(unit 1)
		(exclude_from_sim no)
		(in_bom yes)
		(on_board yes)
		(dnp no)
		(fields_autoplaced yes)
		(property "Reference" "#PWR0134"
			(at 266.7 163.83 0)
			(effects
				(font
					(size 1.27 1.27)
				)
				(hide yes)
			)
		)
		(property "Value" "+1V2"
			(at 266.7 154.94 0)
			(effects
				(font
					(size 1.27 1.27)
				)
			)
		)
		(property "Footprint" ""
			(at 266.7 160.02 0)
			(effects
				(font
					(size 1.27 1.27)
				)
				(hide yes)
			)
		)
		(property "Datasheet" ""
			(at 266.7 160.02 0)
			(effects
				(font
					(size 1.27 1.27)
				)
				(hide yes)
			)
		)
		(property "Description" ""
			(at 266.7 160.02 0)
			(effects
				(font
					(size 1.27 1.27)
				)
				(hide yes)
			)
		)
		(pin "1"
		)
		(instances
			(project "sdi-mipi-video-converter"
				(path ""
					(reference "#PWR0134")
					(unit 1)
				)
			)
		)
	)
	(symbol
		(lib_id "antmicroTestPoints:TP_0.75mm_SMD")
		(at 168.91 198.12 0)
		(unit 1)
		(exclude_from_sim no)
		(in_bom yes)
		(on_board yes)
		(dnp no)
		(fields_autoplaced yes)
		(property "Reference" "TP40"
			(at 173.99 198.1199 0)
			(effects
				(font
					(size 1.27 1.27)
					(thickness 0.15)
				)
				(justify left)
			)
		)
		(property "Value" "TP_0.75mm_SMD"
			(at 186.69 205.74 0)
			(effects
				(font
					(size 1.27 1.27)
					(thickness 0.15)
				)
				(justify left bottom)
				(hide yes)
			)
		)
		(property "Footprint" "antmicro-footprints:TP_SMD_0.75mm"
			(at 186.69 208.28 0)
			(effects
				(font
					(size 1.27 1.27)
					(thickness 0.15)
				)
				(justify left bottom)
				(hide yes)
			)
		)
		(property "Datasheet" ""
			(at 186.69 210.82 0)
			(effects
				(font
					(size 1.27 1.27)
					(thickness 0.15)
				)
				(justify left bottom)
				(hide yes)
			)
		)
		(property "Description" "SMT test point"
			(at 168.91 198.12 0)
			(effects
				(font
					(size 1.27 1.27)
				)
				(hide yes)
			)
		)
		(property "MPN" ""
			(at 186.69 213.36 0)
			(effects
				(font
					(size 1.27 1.27)
					(thickness 0.15)
				)
				(justify left bottom)
				(hide yes)
			)
		)
		(property "Manufacturer" ""
			(at 186.69 215.9 0)
			(effects
				(font
					(size 1.27 1.27)
					(thickness 0.15)
				)
				(justify left bottom)
				(hide yes)
			)
		)
		(property "Author" "Antmicro"
			(at 186.69 218.44 0)
			(effects
				(font
					(size 1.27 1.27)
					(thickness 0.15)
				)
				(justify left bottom)
				(hide yes)
			)
		)
		(property "License" "Apache-2.0"
			(at 186.69 220.98 0)
			(effects
				(font
					(size 1.27 1.27)
					(thickness 0.15)
				)
				(justify left bottom)
				(hide yes)
			)
		)
		(pin "1"
		)
		(instances
			(project "sdi-mipi-video-converter"
				(path ""
					(reference "TP40")
					(unit 1)
				)
			)
		)
	)
	(symbol
		(lib_id "antmicropower:GND")
		(at 62.23 214.63 0)
		(unit 1)
		(exclude_from_sim no)
		(in_bom yes)
		(on_board yes)
		(dnp no)
		(fields_autoplaced yes)
		(property "Reference" "#PWR0108"
			(at 71.12 217.17 0)
			(effects
				(font
					(size 1.27 1.27)
					(thickness 0.15)
				)
				(justify left bottom)
				(hide yes)
			)
		)
		(property "Value" "GND"
			(at 62.23 219.71 0)
			(effects
				(font
					(size 1.27 1.27)
					(thickness 0.15)
				)
			)
		)
		(property "Footprint" ""
			(at 71.12 222.25 0)
			(effects
				(font
					(size 1.27 1.27)
					(thickness 0.15)
				)
				(justify left bottom)
				(hide yes)
			)
		)
		(property "Datasheet" ""
			(at 71.12 227.33 0)
			(effects
				(font
					(size 1.27 1.27)
					(thickness 0.15)
				)
				(justify left bottom)
				(hide yes)
			)
		)
		(property "Description" ""
			(at 62.23 214.63 0)
			(effects
				(font
					(size 1.27 1.27)
				)
				(hide yes)
			)
		)
		(property "Author" "Antmicro"
			(at 71.12 222.25 0)
			(effects
				(font
					(size 1.27 1.27)
					(thickness 0.15)
				)
				(justify left bottom)
				(hide yes)
			)
		)
		(property "License" "Apache-2.0"
			(at 71.12 224.79 0)
			(effects
				(font
					(size 1.27 1.27)
					(thickness 0.15)
				)
				(justify left bottom)
				(hide yes)
			)
		)
		(pin "1"
		)
		(instances
			(project "sdi-mipi-video-converter"
				(path ""
					(reference "#PWR0108")
					(unit 1)
				)
			)
		)
	)
	(symbol
		(lib_id "antmicroResistors0402:R_1k_0402")
		(at 190.5 165.1 90)
		(unit 1)
		(exclude_from_sim no)
		(in_bom yes)
		(on_board yes)
		(dnp no)
		(fields_autoplaced yes)
		(property "Reference" "R139"
			(at 193.04 161.2899 90)
			(effects
				(font
					(size 1.27 1.27)
					(thickness 0.15)
				)
				(justify right)
			)
		)
		(property "Value" "R_1k_0402"
			(at 203.2 144.78 0)
			(effects
				(font
					(size 1.27 1.27)
					(thickness 0.15)
				)
				(justify left bottom)
				(hide yes)
			)
		)
		(property "Footprint" "antmicro-footprints:R_0402_1005Metric"
			(at 205.74 144.78 0)
			(effects
				(font
					(size 1.27 1.27)
					(thickness 0.15)
				)
				(justify left bottom)
				(hide yes)
			)
		)
		(property "Datasheet" "https://www.bourns.com/docs/product-datasheets/cr.pdf"
			(at 208.28 144.78 0)
			(effects
				(font
					(size 1.27 1.27)
					(thickness 0.15)
				)
				(justify left bottom)
				(hide yes)
			)
		)
		(property "Description" "SMD Chip Resistor, 1 kohm, ± 1%, 63 mW, 0402 [1005 Metric], Thick Film, General Purpose"
			(at 190.5 165.1 0)
			(effects
				(font
					(size 1.27 1.27)
				)
				(hide yes)
			)
		)
		(property "Manufacturer" "Bourns"
			(at 213.36 144.78 0)
			(effects
				(font
					(size 1.27 1.27)
					(thickness 0.15)
				)
				(justify left bottom)
				(hide yes)
			)
		)
		(property "MPN" "CR0402-FX-1001GLF"
			(at 210.82 144.78 0)
			(effects
				(font
					(size 1.27 1.27)
					(thickness 0.15)
				)
				(justify left bottom)
				(hide yes)
			)
		)
		(property "Val" "1k"
			(at 193.04 163.8299 90)
			(effects
				(font
					(size 1.27 1.27)
					(thickness 0.15)
				)
				(justify right)
			)
		)
		(property "License" "Apache-2.0"
			(at 215.9 144.78 0)
			(effects
				(font
					(size 1.27 1.27)
					(thickness 0.15)
				)
				(justify left bottom)
				(hide yes)
			)
		)
		(property "Author" "Antmicro"
			(at 218.44 144.78 0)
			(effects
				(font
					(size 1.27 1.27)
					(thickness 0.15)
				)
				(justify left bottom)
				(hide yes)
			)
		)
		(property "Tolerance" "1%"
			(at 200.66 144.78 0)
			(effects
				(font
					(size 1.27 1.27)
				)
				(justify left bottom)
				(hide yes)
			)
		)
		(pin "1"
		)
		(pin "2"
		)
		(instances
			(project "sdi-mipi-video-converter"
				(path ""
					(reference "R139")
					(unit 1)
				)
			)
		)
	)
	(symbol
		(lib_id "antmicropower:GND")
		(at 102.87 180.34 0)
		(unit 1)
		(exclude_from_sim no)
		(in_bom yes)
		(on_board yes)
		(dnp no)
		(fields_autoplaced yes)
		(property "Reference" "#PWR0113"
			(at 111.76 182.88 0)
			(effects
				(font
					(size 1.27 1.27)
					(thickness 0.15)
				)
				(justify left bottom)
				(hide yes)
			)
		)
		(property "Value" "GND"
			(at 102.87 185.42 0)
			(effects
				(font
					(size 1.27 1.27)
					(thickness 0.15)
				)
			)
		)
		(property "Footprint" ""
			(at 111.76 187.96 0)
			(effects
				(font
					(size 1.27 1.27)
					(thickness 0.15)
				)
				(justify left bottom)
				(hide yes)
			)
		)
		(property "Datasheet" ""
			(at 111.76 193.04 0)
			(effects
				(font
					(size 1.27 1.27)
					(thickness 0.15)
				)
				(justify left bottom)
				(hide yes)
			)
		)
		(property "Description" ""
			(at 102.87 180.34 0)
			(effects
				(font
					(size 1.27 1.27)
				)
				(hide yes)
			)
		)
		(property "Author" "Antmicro"
			(at 111.76 187.96 0)
			(effects
				(font
					(size 1.27 1.27)
					(thickness 0.15)
				)
				(justify left bottom)
				(hide yes)
			)
		)
		(property "License" "Apache-2.0"
			(at 111.76 190.5 0)
			(effects
				(font
					(size 1.27 1.27)
					(thickness 0.15)
				)
				(justify left bottom)
				(hide yes)
			)
		)
		(pin "1"
		)
		(instances
			(project "sdi-mipi-video-converter"
				(path ""
					(reference "#PWR0113")
					(unit 1)
				)
			)
		)
	)
	(symbol
		(lib_id "antmicropower:+3.3V")
		(at 261.62 72.39 0)
		(unit 1)
		(exclude_from_sim no)
		(in_bom yes)
		(on_board yes)
		(dnp no)
		(fields_autoplaced yes)
		(property "Reference" "#PWR0143"
			(at 261.62 76.2 0)
			(effects
				(font
					(size 1.27 1.27)
				)
				(hide yes)
			)
		)
		(property "Value" "+3V3"
			(at 261.62 67.31 0)
			(effects
				(font
					(size 1.27 1.27)
				)
			)
		)
		(property "Footprint" ""
			(at 261.62 72.39 0)
			(effects
				(font
					(size 1.27 1.27)
				)
				(hide yes)
			)
		)
		(property "Datasheet" ""
			(at 261.62 72.39 0)
			(effects
				(font
					(size 1.27 1.27)
				)
				(hide yes)
			)
		)
		(property "Description" ""
			(at 261.62 72.39 0)
			(effects
				(font
					(size 1.27 1.27)
				)
				(hide yes)
			)
		)
		(pin "1"
		)
		(instances
			(project "sdi-mipi-video-converter"
				(path ""
					(reference "#PWR0143")
					(unit 1)
				)
			)
		)
	)
	(symbol
		(lib_id "antmicroResonators:Resonator_27MHz_ABM7")
		(at 69.85 181.61 270)
		(mirror x)
		(unit 1)
		(exclude_from_sim no)
		(in_bom yes)
		(on_board yes)
		(dnp no)
		(property "Reference" "Y1"
			(at 68.58 170.18 90)
			(effects
				(font
					(size 1.27 1.27)
					(thickness 0.15)
				)
				(justify left)
			)
		)
		(property "Value" "Oscillator_SMD_27MHz_ABM7"
			(at 58.42 168.275 90)
			(effects
				(font
					(size 1.27 1.27)
					(thickness 0.15)
				)
				(justify left)
			)
		)
		(property "Footprint" "antmicro-footprints:Resonator_SMD_Abracon_ABM7_6x3.5x1.4mm"
			(at 59.69 160.02 0)
			(effects
				(font
					(size 1.27 1.27)
					(thickness 0.15)
				)
				(justify left bottom)
				(hide yes)
			)
		)
		(property "Datasheet" "https://abracon.com/Resonators/abm7.pdf"
			(at 57.15 160.02 0)
			(effects
				(font
					(size 1.27 1.27)
					(thickness 0.15)
				)
				(justify left bottom)
				(hide yes)
			)
		)
		(property "Description" "Crystal, 27 MHz, SMD, 6mm x 3.5mm, 30 ppm, 18 pF, 20 ppm, ABM7"
			(at 69.85 181.61 0)
			(effects
				(font
					(size 1.27 1.27)
				)
				(hide yes)
			)
		)
		(property "MPN" "ABM7-27.000MHZ-D2Y-T"
			(at 54.61 160.02 0)
			(effects
				(font
					(size 1.27 1.27)
					(thickness 0.15)
				)
				(justify left bottom)
				(hide yes)
			)
		)
		(property "Manufacturer" "Abracon"
			(at 52.07 160.02 0)
			(effects
				(font
					(size 1.27 1.27)
					(thickness 0.15)
				)
				(justify left bottom)
				(hide yes)
			)
		)
		(property "Author" "Antmicro"
			(at 49.53 160.02 0)
			(effects
				(font
					(size 1.27 1.27)
					(thickness 0.15)
				)
				(justify left bottom)
				(hide yes)
			)
		)
		(property "License" "Apache-2.0"
			(at 46.99 160.02 0)
			(effects
				(font
					(size 1.27 1.27)
					(thickness 0.15)
				)
				(justify left bottom)
				(hide yes)
			)
		)
		(property "Val" "27 MHz"
			(at 59.69 166.37 0)
			(effects
				(font
					(size 1.27 1.27)
					(thickness 0.15)
				)
				(justify left bottom)
			)
		)
		(pin "1"
		)
		(pin "2"
		)
		(instances
			(project "sdi-mipi-video-converter"
				(path ""
					(reference "Y1")
					(unit 1)
				)
			)
		)
	)
	(symbol
		(lib_id "antmicropower:GND")
		(at 247.65 218.44 0)
		(unit 1)
		(exclude_from_sim no)
		(in_bom yes)
		(on_board yes)
		(dnp no)
		(fields_autoplaced yes)
		(property "Reference" "#PWR0124"
			(at 256.54 220.98 0)
			(effects
				(font
					(size 1.27 1.27)
					(thickness 0.15)
				)
				(justify left bottom)
				(hide yes)
			)
		)
		(property "Value" "GND"
			(at 247.65 223.52 0)
			(effects
				(font
					(size 1.27 1.27)
					(thickness 0.15)
				)
			)
		)
		(property "Footprint" ""
			(at 256.54 226.06 0)
			(effects
				(font
					(size 1.27 1.27)
					(thickness 0.15)
				)
				(justify left bottom)
				(hide yes)
			)
		)
		(property "Datasheet" ""
			(at 256.54 231.14 0)
			(effects
				(font
					(size 1.27 1.27)
					(thickness 0.15)
				)
				(justify left bottom)
				(hide yes)
			)
		)
		(property "Description" ""
			(at 247.65 218.44 0)
			(effects
				(font
					(size 1.27 1.27)
				)
				(hide yes)
			)
		)
		(property "Author" "Antmicro"
			(at 256.54 226.06 0)
			(effects
				(font
					(size 1.27 1.27)
					(thickness 0.15)
				)
				(justify left bottom)
				(hide yes)
			)
		)
		(property "License" "Apache-2.0"
			(at 256.54 228.6 0)
			(effects
				(font
					(size 1.27 1.27)
					(thickness 0.15)
				)
				(justify left bottom)
				(hide yes)
			)
		)
		(pin "1"
		)
		(instances
			(project "sdi-mipi-video-converter"
				(path ""
					(reference "#PWR0124")
					(unit 1)
				)
			)
		)
	)
	(symbol
		(lib_id "antmicropower:GND")
		(at 318.77 220.98 0)
		(unit 1)
		(exclude_from_sim no)
		(in_bom yes)
		(on_board yes)
		(dnp no)
		(fields_autoplaced yes)
		(property "Reference" "#PWR0142"
			(at 327.66 223.52 0)
			(effects
				(font
					(size 1.27 1.27)
					(thickness 0.15)
				)
				(justify left bottom)
				(hide yes)
			)
		)
		(property "Value" "GND"
			(at 318.77 226.06 0)
			(effects
				(font
					(size 1.27 1.27)
					(thickness 0.15)
				)
			)
		)
		(property "Footprint" ""
			(at 327.66 228.6 0)
			(effects
				(font
					(size 1.27 1.27)
					(thickness 0.15)
				)
				(justify left bottom)
				(hide yes)
			)
		)
		(property "Datasheet" ""
			(at 327.66 233.68 0)
			(effects
				(font
					(size 1.27 1.27)
					(thickness 0.15)
				)
				(justify left bottom)
				(hide yes)
			)
		)
		(property "Description" ""
			(at 318.77 220.98 0)
			(effects
				(font
					(size 1.27 1.27)
				)
				(hide yes)
			)
		)
		(property "Author" "Antmicro"
			(at 327.66 228.6 0)
			(effects
				(font
					(size 1.27 1.27)
					(thickness 0.15)
				)
				(justify left bottom)
				(hide yes)
			)
		)
		(property "License" "Apache-2.0"
			(at 327.66 231.14 0)
			(effects
				(font
					(size 1.27 1.27)
					(thickness 0.15)
				)
				(justify left bottom)
				(hide yes)
			)
		)
		(pin "1"
		)
		(instances
			(project "sdi-mipi-video-converter"
				(path ""
					(reference "#PWR0142")
					(unit 1)
				)
			)
		)
	)
	(symbol
		(lib_id "antmicroFPGAChips:CrossLink_LIFCL-40-9BG256C")
		(at 96.52 106.68 0)
		(mirror y)
		(unit 8)
		(exclude_from_sim no)
		(in_bom yes)
		(on_board yes)
		(dnp no)
		(fields_autoplaced yes)
		(property "Reference" "U11"
			(at 73.66 99.06 0)
			(effects
				(font
					(size 1.27 1.27)
					(thickness 0.15)
				)
			)
		)
		(property "Value" "LIFCL-40-9BG256C"
			(at 73.66 99.06 0)
			(effects
				(font
					(size 1.27 1.27)
					(thickness 0.15)
				)
				(hide yes)
			)
		)
		(property "Footprint" "antmicro-footprints:BGA-256_14x14mm_Layout16x16_P0.8mm"
			(at 43.18 114.3 0)
			(effects
				(font
					(size 1.27 1.27)
					(thickness 0.15)
				)
				(justify left bottom)
				(hide yes)
			)
		)
		(property "Datasheet" "https://www.latticesemi.com/-/media/LatticeSemi/Documents/DataSheets/CrossLink/FPGA-DS-02007-2-1-CrossLink-Family-Data-Sheet.ashx?document_id=51662"
			(at 43.18 116.84 0)
			(effects
				(font
					(size 1.27 1.27)
					(thickness 0.15)
				)
				(justify left bottom)
				(hide yes)
			)
		)
		(property "Description" "CrossLink-NX™ Field Programmable Gate Array 256-LFBGA"
			(at 96.52 106.68 0)
			(effects
				(font
					(size 1.27 1.27)
				)
				(hide yes)
			)
		)
		(property "MPN" "LIFCL-40-9BG256C"
			(at 73.66 101.6 0)
			(effects
				(font
					(size 1.27 1.27)
					(thickness 0.15)
				)
			)
		)
		(property "Manufacturer" "Lattice Semiconductor"
			(at 43.18 119.38 0)
			(effects
				(font
					(size 1.27 1.27)
					(thickness 0.15)
				)
				(justify left bottom)
				(hide yes)
			)
		)
		(property "Author" "Antmicro"
			(at 43.18 121.92 0)
			(effects
				(font
					(size 1.27 1.27)
					(thickness 0.15)
				)
				(justify left bottom)
				(hide yes)
			)
		)
		(property "License" "Apache-2.0"
			(at 43.18 124.46 0)
			(effects
				(font
					(size 1.27 1.27)
					(thickness 0.15)
				)
				(justify left bottom)
				(hide yes)
			)
		)
		(pin "B16"
		)
		(pin "C12"
		)
		(pin "C13"
		)
		(pin "C14"
		)
		(pin "C15"
		)
		(pin "C16"
		)
		(pin "D11"
		)
		(pin "D12"
		)
		(pin "D13"
		)
		(pin "D15"
		)
		(pin "D16"
		)
		(pin "E15"
		)
		(pin "E16"
		)
		(pin "D10"
		)
		(pin "E10"
		)
		(pin "E11"
		)
		(pin "E12"
		)
		(pin "E13"
		)
		(pin "E14"
		)
		(pin "E9"
		)
		(pin "F10"
		)
		(pin "F11"
		)
		(pin "F13"
		)
		(pin "F14"
		)
		(pin "F15"
		)
		(pin "F16"
		)
		(pin "F9"
		)
		(pin "G10"
		)
		(pin "G11"
		)
		(pin "G12"
		)
		(pin "G13"
		)
		(pin "G14"
		)
		(pin "G15"
		)
		(pin "G16"
		)
		(pin "G9"
		)
		(pin "H10"
		)
		(pin "H11"
		)
		(pin "H12"
		)
		(pin "H13"
		)
		(pin "H14"
		)
		(pin "H15"
		)
		(pin "H16"
		)
		(pin "J11"
		)
		(pin "J12"
		)
		(pin "J13"
		)
		(pin "J15"
		)
		(pin "J16"
		)
		(pin "K11"
		)
		(pin "K12"
		)
		(pin "L10"
		)
		(pin "L11"
		)
		(pin "L12"
		)
		(pin "M11"
		)
		(pin "M12"
		)
		(pin "M13"
		)
		(pin "M14"
		)
		(pin "M15"
		)
		(pin "M16"
		)
		(pin "N11"
		)
		(pin "N12"
		)
		(pin "N13"
		)
		(pin "N14"
		)
		(pin "N15"
		)
		(pin "N16"
		)
		(pin "P10"
		)
		(pin "P11"
		)
		(pin "P12"
		)
		(pin "P14"
		)
		(pin "P15"
		)
		(pin "P16"
		)
		(pin "R10"
		)
		(pin "R11"
		)
		(pin "R12"
		)
		(pin "R13"
		)
		(pin "R14"
		)
		(pin "R15"
		)
		(pin "R16"
		)
		(pin "T11"
		)
		(pin "T12"
		)
		(pin "T13"
		)
		(pin "T14"
		)
		(pin "T15"
		)
		(pin "L8"
		)
		(pin "L9"
		)
		(pin "M10"
		)
		(pin "M8"
		)
		(pin "M9"
		)
		(pin "N10"
		)
		(pin "N6"
		)
		(pin "N8"
		)
		(pin "N9"
		)
		(pin "P4"
		)
		(pin "P5"
		)
		(pin "P6"
		)
		(pin "P7"
		)
		(pin "P8"
		)
		(pin "P9"
		)
		(pin "R1"
		)
		(pin "R2"
		)
		(pin "R3"
		)
		(pin "R4"
		)
		(pin "R5"
		)
		(pin "R6"
		)
		(pin "R7"
		)
		(pin "R8"
		)
		(pin "R9"
		)
		(pin "T10"
		)
		(pin "T2"
		)
		(pin "T3"
		)
		(pin "T4"
		)
		(pin "T5"
		)
		(pin "T6"
		)
		(pin "T7"
		)
		(pin "T8"
		)
		(pin "T9"
		)
		(pin "K7"
		)
		(pin "L6"
		)
		(pin "L7"
		)
		(pin "M4"
		)
		(pin "M7"
		)
		(pin "N3"
		)
		(pin "N4"
		)
		(pin "N5"
		)
		(pin "P1"
		)
		(pin "P2"
		)
		(pin "P3"
		)
		(pin "H1"
		)
		(pin "H2"
		)
		(pin "H3"
		)
		(pin "H4"
		)
		(pin "H5"
		)
		(pin "H6"
		)
		(pin "J1"
		)
		(pin "J2"
		)
		(pin "J4"
		)
		(pin "J5"
		)
		(pin "J6"
		)
		(pin "K1"
		)
		(pin "K2"
		)
		(pin "K3"
		)
		(pin "K4"
		)
		(pin "K5"
		)
		(pin "K6"
		)
		(pin "L1"
		)
		(pin "L2"
		)
		(pin "L3"
		)
		(pin "L4"
		)
		(pin "L5"
		)
		(pin "M1"
		)
		(pin "M2"
		)
		(pin "M3"
		)
		(pin "N1"
		)
		(pin "N2"
		)
		(pin "D4"
		)
		(pin "D5"
		)
		(pin "D6"
		)
		(pin "E4"
		)
		(pin "E5"
		)
		(pin "E6"
		)
		(pin "F4"
		)
		(pin "F5"
		)
		(pin "F6"
		)
		(pin "G3"
		)
		(pin "G4"
		)
		(pin "G6"
		)
		(pin "B1"
		)
		(pin "B2"
		)
		(pin "C1"
		)
		(pin "C2"
		)
		(pin "D1"
		)
		(pin "D2"
		)
		(pin "E1"
		)
		(pin "E2"
		)
		(pin "F1"
		)
		(pin "F2"
		)
		(pin "A3"
		)
		(pin "A4"
		)
		(pin "A5"
		)
		(pin "A6"
		)
		(pin "A7"
		)
		(pin "B3"
		)
		(pin "B4"
		)
		(pin "B5"
		)
		(pin "B6"
		)
		(pin "B7"
		)
		(pin "K13"
		)
		(pin "K14"
		)
		(pin "K15"
		)
		(pin "K16"
		)
		(pin "L13"
		)
		(pin "L14"
		)
		(pin "L15"
		)
		(pin "L16"
		)
		(pin "A11"
		)
		(pin "A12"
		)
		(pin "A14"
		)
		(pin "A15"
		)
		(pin "A9"
		)
		(pin "B12"
		)
		(pin "B9"
		)
		(pin "C11"
		)
		(pin "A1"
		)
		(pin "A10"
		)
		(pin "A13"
		)
		(pin "A16"
		)
		(pin "A2"
		)
		(pin "A8"
		)
		(pin "B10"
		)
		(pin "B11"
		)
		(pin "B13"
		)
		(pin "B14"
		)
		(pin "B15"
		)
		(pin "B8"
		)
		(pin "C10"
		)
		(pin "C3"
		)
		(pin "C4"
		)
		(pin "C5"
		)
		(pin "C6"
		)
		(pin "C7"
		)
		(pin "C8"
		)
		(pin "C9"
		)
		(pin "D14"
		)
		(pin "D3"
		)
		(pin "D7"
		)
		(pin "D8"
		)
		(pin "D9"
		)
		(pin "E3"
		)
		(pin "E7"
		)
		(pin "E8"
		)
		(pin "F12"
		)
		(pin "F3"
		)
		(pin "F7"
		)
		(pin "F8"
		)
		(pin "G1"
		)
		(pin "G2"
		)
		(pin "G5"
		)
		(pin "G7"
		)
		(pin "G8"
		)
		(pin "H7"
		)
		(pin "H8"
		)
		(pin "H9"
		)
		(pin "J10"
		)
		(pin "J14"
		)
		(pin "J3"
		)
		(pin "J7"
		)
		(pin "J8"
		)
		(pin "J9"
		)
		(pin "K10"
		)
		(pin "K8"
		)
		(pin "K9"
		)
		(pin "M5"
		)
		(pin "M6"
		)
		(pin "N7"
		)
		(pin "P13"
		)
		(pin "T1"
		)
		(pin "T16"
		)
		(instances
			(project "sdi-mipi-video-converter"
				(path ""
					(reference "U11")
					(unit 8)
				)
			)
		)
	)
	(symbol
		(lib_id "antmicroResistors0603:R_200R_0603")
		(at 151.13 248.92 90)
		(unit 1)
		(exclude_from_sim no)
		(in_bom yes)
		(on_board yes)
		(dnp no)
		(fields_autoplaced yes)
		(property "Reference" "R100"
			(at 153.67 245.1099 90)
			(effects
				(font
					(size 1.27 1.27)
					(thickness 0.15)
				)
				(justify right)
			)
		)
		(property "Value" "R_200R_0603"
			(at 163.83 228.6 0)
			(effects
				(font
					(size 1.27 1.27)
					(thickness 0.15)
				)
				(justify left bottom)
				(hide yes)
			)
		)
		(property "Footprint" "antmicro-footprints:R_0603_1608Metric"
			(at 166.37 228.6 0)
			(effects
				(font
					(size 1.27 1.27)
					(thickness 0.15)
				)
				(justify left bottom)
				(hide yes)
			)
		)
		(property "Datasheet" "https://www.bourns.com/docs/product-datasheets/cr.pdf"
			(at 168.91 228.6 0)
			(effects
				(font
					(size 1.27 1.27)
					(thickness 0.15)
				)
				(justify left bottom)
				(hide yes)
			)
		)
		(property "Description" "SMD Chip Resistor, 200 ohm, ± 1%, 100 mW, 0603 [1608 Metric], Thick Film, General Purpose"
			(at 151.13 248.92 0)
			(effects
				(font
					(size 1.27 1.27)
				)
				(hide yes)
			)
		)
		(property "Manufacturer" "Bourns"
			(at 173.99 228.6 0)
			(effects
				(font
					(size 1.27 1.27)
					(thickness 0.15)
				)
				(justify left bottom)
				(hide yes)
			)
		)
		(property "MPN" "CR0603-FX-2000ELF"
			(at 171.45 228.6 0)
			(effects
				(font
					(size 1.27 1.27)
					(thickness 0.15)
				)
				(justify left bottom)
				(hide yes)
			)
		)
		(property "Val" "200R"
			(at 153.67 247.6499 90)
			(effects
				(font
					(size 1.27 1.27)
					(thickness 0.15)
				)
				(justify right)
			)
		)
		(property "License" "Apache-2.0"
			(at 176.53 228.6 0)
			(effects
				(font
					(size 1.27 1.27)
					(thickness 0.15)
				)
				(justify left bottom)
				(hide yes)
			)
		)
		(property "Author" "Antmicro"
			(at 179.07 228.6 0)
			(effects
				(font
					(size 1.27 1.27)
					(thickness 0.15)
				)
				(justify left bottom)
				(hide yes)
			)
		)
		(property "Tolerance" "1%"
			(at 161.29 228.6 0)
			(effects
				(font
					(size 1.27 1.27)
				)
				(justify left bottom)
				(hide yes)
			)
		)
		(pin "1"
		)
		(pin "2"
		)
		(instances
			(project "sdi-mipi-video-converter"
				(path ""
					(reference "R100")
					(unit 1)
				)
			)
		)
	)
	(symbol
		(lib_id "antmicropower:+1V2")
		(at 247.65 229.87 0)
		(unit 1)
		(exclude_from_sim no)
		(in_bom yes)
		(on_board yes)
		(dnp no)
		(fields_autoplaced yes)
		(property "Reference" "#PWR0125"
			(at 247.65 233.68 0)
			(effects
				(font
					(size 1.27 1.27)
				)
				(hide yes)
			)
		)
		(property "Value" "+1V2"
			(at 245.11 228.5999 0)
			(effects
				(font
					(size 1.27 1.27)
				)
				(justify right)
			)
		)
		(property "Footprint" ""
			(at 247.65 229.87 0)
			(effects
				(font
					(size 1.27 1.27)
				)
				(hide yes)
			)
		)
		(property "Datasheet" ""
			(at 247.65 229.87 0)
			(effects
				(font
					(size 1.27 1.27)
				)
				(hide yes)
			)
		)
		(property "Description" ""
			(at 247.65 229.87 0)
			(effects
				(font
					(size 1.27 1.27)
				)
				(hide yes)
			)
		)
		(pin "1"
		)
		(instances
			(project "sdi-mipi-video-converter"
				(path ""
					(reference "#PWR0125")
					(unit 1)
				)
			)
		)
	)
	(symbol
		(lib_id "antmicroLEDIndicationDiscrete:LED_G_0603_LTST-C190GKT")
		(at 162.56 256.54 270)
		(mirror x)
		(unit 1)
		(exclude_from_sim no)
		(in_bom yes)
		(on_board yes)
		(dnp no)
		(fields_autoplaced yes)
		(property "Reference" "D8"
			(at 166.37 252.73 90)
			(effects
				(font
					(size 1.27 1.27)
					(thickness 0.15)
				)
				(justify left)
			)
		)
		(property "Value" "LED_G_0603_LTST-C190GKT"
			(at 166.37 255.27 90)
			(effects
				(font
					(size 1.27 1.27)
					(thickness 0.15)
				)
				(justify left)
			)
		)
		(property "Footprint" "antmicro-footprints:LED_0603_1608Metric_G"
			(at 152.4 233.68 0)
			(effects
				(font
					(size 1.27 1.27)
					(thickness 0.15)
				)
				(justify left bottom)
				(hide yes)
			)
		)
		(property "Datasheet" "https://media.digikey.com/pdf/Data%20Sheets/Lite-On%20PDFs/LTST-C190GKT.pdf"
			(at 149.86 233.68 0)
			(effects
				(font
					(size 1.27 1.27)
					(thickness 0.15)
				)
				(justify left bottom)
				(hide yes)
			)
		)
		(property "Description" "LED, Green, SMD, 0603, 20 mA, 2.1 V, 569 nm"
			(at 162.56 256.54 0)
			(effects
				(font
					(size 1.27 1.27)
				)
				(hide yes)
			)
		)
		(property "MPN" "LTST-C190GKT"
			(at 147.32 233.68 0)
			(effects
				(font
					(size 1.27 1.27)
					(thickness 0.15)
				)
				(justify left bottom)
				(hide yes)
			)
		)
		(property "Manufacturer" "Lite-On"
			(at 144.78 233.68 0)
			(effects
				(font
					(size 1.27 1.27)
					(thickness 0.15)
				)
				(justify left bottom)
				(hide yes)
			)
		)
		(property "Author" "Antmicro"
			(at 142.24 233.68 0)
			(effects
				(font
					(size 1.27 1.27)
					(thickness 0.15)
				)
				(justify left bottom)
				(hide yes)
			)
		)
		(property "License" "Apache-2.0"
			(at 139.7 233.68 0)
			(effects
				(font
					(size 1.27 1.27)
					(thickness 0.15)
				)
				(justify left bottom)
				(hide yes)
			)
		)
		(property "Color" "Green"
			(at 166.37 256.5399 90)
			(effects
				(font
					(size 1.27 1.27)
				)
				(justify left)
				(hide yes)
			)
		)
		(pin "1"
		)
		(pin "2"
		)
		(instances
			(project "sdi-mipi-video-converter"
				(path ""
					(reference "D8")
					(unit 1)
				)
			)
		)
	)
	(symbol
		(lib_id "antmicroCapacitors0402:C_100n_0402")
		(at 259.08 191.77 90)
		(unit 1)
		(exclude_from_sim no)
		(in_bom yes)
		(on_board yes)
		(dnp no)
		(fields_autoplaced yes)
		(property "Reference" "C66"
			(at 261.62 187.9535 90)
			(effects
				(font
					(size 1.27 1.27)
					(thickness 0.15)
				)
				(justify right)
			)
		)
		(property "Value" "C_100n_0402"
			(at 269.24 171.45 0)
			(effects
				(font
					(size 1.27 1.27)
					(thickness 0.15)
				)
				(justify left bottom)
				(hide yes)
			)
		)
		(property "Footprint" "antmicro-footprints:C_0402_1005Metric"
			(at 271.78 171.45 0)
			(effects
				(font
					(size 1.27 1.27)
					(thickness 0.15)
				)
				(justify left bottom)
				(hide yes)
			)
		)
		(property "Datasheet" "https://www.murata.com/products/productdetail?partno=GRM155R61H104KE14%23"
			(at 274.32 171.45 0)
			(effects
				(font
					(size 1.27 1.27)
					(thickness 0.15)
				)
				(justify left bottom)
				(hide yes)
			)
		)
		(property "Description" "SMD Multilayer Ceramic Capacitor, 0.1 µF, 50 V, 0402 [1005 Metric], ± 10%, X5R, GRM Series"
			(at 259.08 191.77 0)
			(effects
				(font
					(size 1.27 1.27)
				)
				(hide yes)
			)
		)
		(property "Manufacturer" "Murata"
			(at 279.4 171.45 0)
			(effects
				(font
					(size 1.27 1.27)
					(thickness 0.15)
				)
				(justify left bottom)
				(hide yes)
			)
		)
		(property "MPN" "GRM155R61H104KE14D"
			(at 276.86 171.45 0)
			(effects
				(font
					(size 1.27 1.27)
					(thickness 0.15)
				)
				(justify left bottom)
				(hide yes)
			)
		)
		(property "Val" "100n"
			(at 261.62 190.4935 90)
			(effects
				(font
					(size 1.27 1.27)
					(thickness 0.15)
				)
				(justify right)
			)
		)
		(property "License" "Apache-2.0"
			(at 281.94 171.45 0)
			(effects
				(font
					(size 1.27 1.27)
					(thickness 0.15)
				)
				(justify left bottom)
				(hide yes)
			)
		)
		(property "Author" "Antmicro"
			(at 284.48 171.45 0)
			(effects
				(font
					(size 1.27 1.27)
					(thickness 0.15)
				)
				(justify left bottom)
				(hide yes)
			)
		)
		(property "Voltage" "50V"
			(at 287.02 171.45 0)
			(effects
				(font
					(size 1.27 1.27)
				)
				(justify left bottom)
				(hide yes)
			)
		)
		(property "Dielectric" "X5R"
			(at 289.56 171.45 0)
			(effects
				(font
					(size 1.27 1.27)
				)
				(justify left bottom)
				(hide yes)
			)
		)
		(pin "1"
		)
		(pin "2"
		)
		(instances
			(project "sdi-mipi-video-converter"
				(path ""
					(reference "C66")
					(unit 1)
				)
			)
		)
	)
	(symbol
		(lib_id "antmicroInterfaceControllers:GS2971A")
		(at 119.38 167.64 0)
		(unit 2)
		(exclude_from_sim no)
		(in_bom yes)
		(on_board yes)
		(dnp no)
		(fields_autoplaced yes)
		(property "Reference" "U15"
			(at 135.255 160.02 0)
			(effects
				(font
					(size 1.27 1.27)
					(thickness 0.15)
				)
			)
		)
		(property "Value" "GS2971A"
			(at 135.255 162.56 0)
			(effects
				(font
					(size 1.27 1.27)
					(thickness 0.15)
				)
			)
		)
		(property "Footprint" "antmicro-footprints:BGA-100_11x11mm_Layout10x10_P1mm"
			(at 175.26 175.26 0)
			(effects
				(font
					(size 1.27 1.27)
					(thickness 0.15)
				)
				(justify left bottom)
				(hide yes)
			)
		)
		(property "Datasheet" "https://semtech.my.salesforce.com/sfc/p/#E0000000JelG/a/44000000MD3i/kpmMkrmUWgHlbCOwdLzVohMm1SDPoVH85guEGK.KXTc"
			(at 175.26 177.8 0)
			(effects
				(font
					(size 1.27 1.27)
					(thickness 0.15)
				)
				(justify left bottom)
				(hide yes)
			)
		)
		(property "Description" "SDI receiver"
			(at 119.38 167.64 0)
			(effects
				(font
					(size 1.27 1.27)
				)
				(hide yes)
			)
		)
		(property "MPN" "GS2971A"
			(at 175.26 180.34 0)
			(effects
				(font
					(size 1.27 1.27)
					(thickness 0.15)
				)
				(justify left bottom)
				(hide yes)
			)
		)
		(property "Manufacturer" "Semtech"
			(at 175.26 182.88 0)
			(effects
				(font
					(size 1.27 1.27)
					(thickness 0.15)
				)
				(justify left bottom)
				(hide yes)
			)
		)
		(property "Author" "Antmicro"
			(at 175.26 185.42 0)
			(effects
				(font
					(size 1.27 1.27)
					(thickness 0.15)
				)
				(justify left bottom)
				(hide yes)
			)
		)
		(property "License" "Apache-2.0"
			(at 175.26 187.96 0)
			(effects
				(font
					(size 1.27 1.27)
					(thickness 0.15)
				)
				(justify left bottom)
				(hide yes)
			)
		)
		(pin "A10"
		)
		(pin "A5"
		)
		(pin "A6"
		)
		(pin "A8"
		)
		(pin "A9"
		)
		(pin "B10"
		)
		(pin "B5"
		)
		(pin "B6"
		)
		(pin "B8"
		)
		(pin "B9"
		)
		(pin "C10"
		)
		(pin "C5"
		)
		(pin "C6"
		)
		(pin "C8"
		)
		(pin "C9"
		)
		(pin "E10"
		)
		(pin "E9"
		)
		(pin "F10"
		)
		(pin "F9"
		)
		(pin "H10"
		)
		(pin "H4"
		)
		(pin "H9"
		)
		(pin "J1"
		)
		(pin "J10"
		)
		(pin "J3"
		)
		(pin "J4"
		)
		(pin "J5"
		)
		(pin "J8"
		)
		(pin "J9"
		)
		(pin "K1"
		)
		(pin "K10"
		)
		(pin "K3"
		)
		(pin "K4"
		)
		(pin "K5"
		)
		(pin "K8"
		)
		(pin "K9"
		)
		(pin "A1"
		)
		(pin "A2"
		)
		(pin "A3"
		)
		(pin "B3"
		)
		(pin "C1"
		)
		(pin "C7"
		)
		(pin "D1"
		)
		(pin "D7"
		)
		(pin "D8"
		)
		(pin "E7"
		)
		(pin "E8"
		)
		(pin "F1"
		)
		(pin "F2"
		)
		(pin "F7"
		)
		(pin "F8"
		)
		(pin "G1"
		)
		(pin "G3"
		)
		(pin "G7"
		)
		(pin "G8"
		)
		(pin "H3"
		)
		(pin "H5"
		)
		(pin "H6"
		)
		(pin "H7"
		)
		(pin "H8"
		)
		(pin "J2"
		)
		(pin "J6"
		)
		(pin "K2"
		)
		(pin "K6"
		)
		(pin "A4"
		)
		(pin "A7"
		)
		(pin "B1"
		)
		(pin "B2"
		)
		(pin "B4"
		)
		(pin "B7"
		)
		(pin "C2"
		)
		(pin "C3"
		)
		(pin "C4"
		)
		(pin "D10"
		)
		(pin "D2"
		)
		(pin "D3"
		)
		(pin "D4"
		)
		(pin "D5"
		)
		(pin "D6"
		)
		(pin "D9"
		)
		(pin "E1"
		)
		(pin "E2"
		)
		(pin "E3"
		)
		(pin "E4"
		)
		(pin "E5"
		)
		(pin "E6"
		)
		(pin "F3"
		)
		(pin "F4"
		)
		(pin "F5"
		)
		(pin "F6"
		)
		(pin "G10"
		)
		(pin "G2"
		)
		(pin "G4"
		)
		(pin "G5"
		)
		(pin "G6"
		)
		(pin "G9"
		)
		(pin "H1"
		)
		(pin "H2"
		)
		(pin "J7"
		)
		(pin "K7"
		)
		(instances
			(project "sdi-mipi-video-converter"
				(path ""
					(reference "U15")
					(unit 2)
				)
			)
		)
	)
	(symbol
		(lib_id "antmicroFPGAChips:CrossLink_LIFCL-40-9BG256C")
		(at 96.52 24.13 0)
		(mirror y)
		(unit 7)
		(exclude_from_sim no)
		(in_bom yes)
		(on_board yes)
		(dnp no)
		(fields_autoplaced yes)
		(property "Reference" "U11"
			(at 74.295 16.51 0)
			(effects
				(font
					(size 1.27 1.27)
					(thickness 0.15)
				)
			)
		)
		(property "Value" "LIFCL-40-9BG256C"
			(at 74.295 16.51 0)
			(effects
				(font
					(size 1.27 1.27)
					(thickness 0.15)
				)
				(hide yes)
			)
		)
		(property "Footprint" "antmicro-footprints:BGA-256_14x14mm_Layout16x16_P0.8mm"
			(at 43.18 31.75 0)
			(effects
				(font
					(size 1.27 1.27)
					(thickness 0.15)
				)
				(justify left bottom)
				(hide yes)
			)
		)
		(property "Datasheet" "https://www.latticesemi.com/-/media/LatticeSemi/Documents/DataSheets/CrossLink/FPGA-DS-02007-2-1-CrossLink-Family-Data-Sheet.ashx?document_id=51662"
			(at 43.18 34.29 0)
			(effects
				(font
					(size 1.27 1.27)
					(thickness 0.15)
				)
				(justify left bottom)
				(hide yes)
			)
		)
		(property "Description" "CrossLink-NX™ Field Programmable Gate Array 256-LFBGA"
			(at 96.52 24.13 0)
			(effects
				(font
					(size 1.27 1.27)
				)
				(hide yes)
			)
		)
		(property "MPN" "LIFCL-40-9BG256C"
			(at 74.295 19.05 0)
			(effects
				(font
					(size 1.27 1.27)
					(thickness 0.15)
				)
			)
		)
		(property "Manufacturer" "Lattice Semiconductor"
			(at 43.18 36.83 0)
			(effects
				(font
					(size 1.27 1.27)
					(thickness 0.15)
				)
				(justify left bottom)
				(hide yes)
			)
		)
		(property "Author" "Antmicro"
			(at 43.18 39.37 0)
			(effects
				(font
					(size 1.27 1.27)
					(thickness 0.15)
				)
				(justify left bottom)
				(hide yes)
			)
		)
		(property "License" "Apache-2.0"
			(at 43.18 41.91 0)
			(effects
				(font
					(size 1.27 1.27)
					(thickness 0.15)
				)
				(justify left bottom)
				(hide yes)
			)
		)
		(pin "B16"
		)
		(pin "C12"
		)
		(pin "C13"
		)
		(pin "C14"
		)
		(pin "C15"
		)
		(pin "C16"
		)
		(pin "D11"
		)
		(pin "D12"
		)
		(pin "D13"
		)
		(pin "D15"
		)
		(pin "D16"
		)
		(pin "E15"
		)
		(pin "E16"
		)
		(pin "D10"
		)
		(pin "E10"
		)
		(pin "E11"
		)
		(pin "E12"
		)
		(pin "E13"
		)
		(pin "E14"
		)
		(pin "E9"
		)
		(pin "F10"
		)
		(pin "F11"
		)
		(pin "F13"
		)
		(pin "F14"
		)
		(pin "F15"
		)
		(pin "F16"
		)
		(pin "F9"
		)
		(pin "G10"
		)
		(pin "G11"
		)
		(pin "G12"
		)
		(pin "G13"
		)
		(pin "G14"
		)
		(pin "G15"
		)
		(pin "G16"
		)
		(pin "G9"
		)
		(pin "H10"
		)
		(pin "H11"
		)
		(pin "H12"
		)
		(pin "H13"
		)
		(pin "H14"
		)
		(pin "H15"
		)
		(pin "H16"
		)
		(pin "J11"
		)
		(pin "J12"
		)
		(pin "J13"
		)
		(pin "J15"
		)
		(pin "J16"
		)
		(pin "K11"
		)
		(pin "K12"
		)
		(pin "L10"
		)
		(pin "L11"
		)
		(pin "L12"
		)
		(pin "M11"
		)
		(pin "M12"
		)
		(pin "M13"
		)
		(pin "M14"
		)
		(pin "M15"
		)
		(pin "M16"
		)
		(pin "N11"
		)
		(pin "N12"
		)
		(pin "N13"
		)
		(pin "N14"
		)
		(pin "N15"
		)
		(pin "N16"
		)
		(pin "P10"
		)
		(pin "P11"
		)
		(pin "P12"
		)
		(pin "P14"
		)
		(pin "P15"
		)
		(pin "P16"
		)
		(pin "R10"
		)
		(pin "R11"
		)
		(pin "R12"
		)
		(pin "R13"
		)
		(pin "R14"
		)
		(pin "R15"
		)
		(pin "R16"
		)
		(pin "T11"
		)
		(pin "T12"
		)
		(pin "T13"
		)
		(pin "T14"
		)
		(pin "T15"
		)
		(pin "L8"
		)
		(pin "L9"
		)
		(pin "M10"
		)
		(pin "M8"
		)
		(pin "M9"
		)
		(pin "N10"
		)
		(pin "N6"
		)
		(pin "N8"
		)
		(pin "N9"
		)
		(pin "P4"
		)
		(pin "P5"
		)
		(pin "P6"
		)
		(pin "P7"
		)
		(pin "P8"
		)
		(pin "P9"
		)
		(pin "R1"
		)
		(pin "R2"
		)
		(pin "R3"
		)
		(pin "R4"
		)
		(pin "R5"
		)
		(pin "R6"
		)
		(pin "R7"
		)
		(pin "R8"
		)
		(pin "R9"
		)
		(pin "T10"
		)
		(pin "T2"
		)
		(pin "T3"
		)
		(pin "T4"
		)
		(pin "T5"
		)
		(pin "T6"
		)
		(pin "T7"
		)
		(pin "T8"
		)
		(pin "T9"
		)
		(pin "K7"
		)
		(pin "L6"
		)
		(pin "L7"
		)
		(pin "M4"
		)
		(pin "M7"
		)
		(pin "N3"
		)
		(pin "N4"
		)
		(pin "N5"
		)
		(pin "P1"
		)
		(pin "P2"
		)
		(pin "P3"
		)
		(pin "H1"
		)
		(pin "H2"
		)
		(pin "H3"
		)
		(pin "H4"
		)
		(pin "H5"
		)
		(pin "H6"
		)
		(pin "J1"
		)
		(pin "J2"
		)
		(pin "J4"
		)
		(pin "J5"
		)
		(pin "J6"
		)
		(pin "K1"
		)
		(pin "K2"
		)
		(pin "K3"
		)
		(pin "K4"
		)
		(pin "K5"
		)
		(pin "K6"
		)
		(pin "L1"
		)
		(pin "L2"
		)
		(pin "L3"
		)
		(pin "L4"
		)
		(pin "L5"
		)
		(pin "M1"
		)
		(pin "M2"
		)
		(pin "M3"
		)
		(pin "N1"
		)
		(pin "N2"
		)
		(pin "D4"
		)
		(pin "D5"
		)
		(pin "D6"
		)
		(pin "E4"
		)
		(pin "E5"
		)
		(pin "E6"
		)
		(pin "F4"
		)
		(pin "F5"
		)
		(pin "F6"
		)
		(pin "G3"
		)
		(pin "G4"
		)
		(pin "G6"
		)
		(pin "B1"
		)
		(pin "B2"
		)
		(pin "C1"
		)
		(pin "C2"
		)
		(pin "D1"
		)
		(pin "D2"
		)
		(pin "E1"
		)
		(pin "E2"
		)
		(pin "F1"
		)
		(pin "F2"
		)
		(pin "A3"
		)
		(pin "A4"
		)
		(pin "A5"
		)
		(pin "A6"
		)
		(pin "A7"
		)
		(pin "B3"
		)
		(pin "B4"
		)
		(pin "B5"
		)
		(pin "B6"
		)
		(pin "B7"
		)
		(pin "K13"
		)
		(pin "K14"
		)
		(pin "K15"
		)
		(pin "K16"
		)
		(pin "L13"
		)
		(pin "L14"
		)
		(pin "L15"
		)
		(pin "L16"
		)
		(pin "A11"
		)
		(pin "A12"
		)
		(pin "A14"
		)
		(pin "A15"
		)
		(pin "A9"
		)
		(pin "B12"
		)
		(pin "B9"
		)
		(pin "C11"
		)
		(pin "A1"
		)
		(pin "A10"
		)
		(pin "A13"
		)
		(pin "A16"
		)
		(pin "A2"
		)
		(pin "A8"
		)
		(pin "B10"
		)
		(pin "B11"
		)
		(pin "B13"
		)
		(pin "B14"
		)
		(pin "B15"
		)
		(pin "B8"
		)
		(pin "C10"
		)
		(pin "C3"
		)
		(pin "C4"
		)
		(pin "C5"
		)
		(pin "C6"
		)
		(pin "C7"
		)
		(pin "C8"
		)
		(pin "C9"
		)
		(pin "D14"
		)
		(pin "D3"
		)
		(pin "D7"
		)
		(pin "D8"
		)
		(pin "D9"
		)
		(pin "E3"
		)
		(pin "E7"
		)
		(pin "E8"
		)
		(pin "F12"
		)
		(pin "F3"
		)
		(pin "F7"
		)
		(pin "F8"
		)
		(pin "G1"
		)
		(pin "G2"
		)
		(pin "G5"
		)
		(pin "G7"
		)
		(pin "G8"
		)
		(pin "H7"
		)
		(pin "H8"
		)
		(pin "H9"
		)
		(pin "J10"
		)
		(pin "J14"
		)
		(pin "J3"
		)
		(pin "J7"
		)
		(pin "J8"
		)
		(pin "J9"
		)
		(pin "K10"
		)
		(pin "K8"
		)
		(pin "K9"
		)
		(pin "M5"
		)
		(pin "M6"
		)
		(pin "N7"
		)
		(pin "P13"
		)
		(pin "T1"
		)
		(pin "T16"
		)
		(instances
			(project "sdi-mipi-video-converter"
				(path ""
					(reference "U11")
					(unit 7)
				)
			)
		)
	)
	(symbol
		(lib_id "antmicropower:+3.3V")
		(at 115.57 102.87 0)
		(unit 1)
		(exclude_from_sim no)
		(in_bom yes)
		(on_board yes)
		(dnp no)
		(fields_autoplaced yes)
		(property "Reference" "#PWR0114"
			(at 115.57 106.68 0)
			(effects
				(font
					(size 1.27 1.27)
				)
				(hide yes)
			)
		)
		(property "Value" "+3V3"
			(at 115.57 97.79 0)
			(effects
				(font
					(size 1.27 1.27)
				)
			)
		)
		(property "Footprint" ""
			(at 115.57 102.87 0)
			(effects
				(font
					(size 1.27 1.27)
				)
				(hide yes)
			)
		)
		(property "Datasheet" ""
			(at 115.57 102.87 0)
			(effects
				(font
					(size 1.27 1.27)
				)
				(hide yes)
			)
		)
		(property "Description" ""
			(at 115.57 102.87 0)
			(effects
				(font
					(size 1.27 1.27)
				)
				(hide yes)
			)
		)
		(pin "1"
		)
		(instances
			(project "sdi-mipi-video-converter"
				(path ""
					(reference "#PWR0114")
					(unit 1)
				)
			)
		)
	)
	(symbol
		(lib_id "antmicroCapacitors0402:C_47n_0402")
		(at 96.52 173.99 90)
		(mirror x)
		(unit 1)
		(exclude_from_sim no)
		(in_bom yes)
		(on_board yes)
		(dnp no)
		(property "Reference" "C55"
			(at 97.155 174.625 90)
			(effects
				(font
					(size 1.27 1.27)
					(thickness 0.15)
				)
				(justify right)
			)
		)
		(property "Value" "C_47n_0402"
			(at 106.68 194.31 0)
			(effects
				(font
					(size 1.27 1.27)
					(thickness 0.15)
				)
				(justify left bottom)
				(hide yes)
			)
		)
		(property "Footprint" "antmicro-footprints:C_0402_1005Metric"
			(at 109.22 194.31 0)
			(effects
				(font
					(size 1.27 1.27)
					(thickness 0.15)
				)
				(justify left bottom)
				(hide yes)
			)
		)
		(property "Datasheet" "https://www.murata.com/en-us/products/productdetail?partno=GRM155R61C473KA01%23"
			(at 111.76 194.31 0)
			(effects
				(font
					(size 1.27 1.27)
					(thickness 0.15)
				)
				(justify left bottom)
				(hide yes)
			)
		)
		(property "Description" "SMD Multilayer Ceramic Capacitor, 47000 pF, 16 V, 0402 [1005 Metric], ± 10%, X5R, MC"
			(at 96.52 173.99 0)
			(effects
				(font
					(size 1.27 1.27)
				)
				(hide yes)
			)
		)
		(property "Manufacturer" "Murata"
			(at 116.84 194.31 0)
			(effects
				(font
					(size 1.27 1.27)
					(thickness 0.15)
				)
				(justify left bottom)
				(hide yes)
			)
		)
		(property "MPN" "GRM155R61C473KA01D"
			(at 114.3 194.31 0)
			(effects
				(font
					(size 1.27 1.27)
					(thickness 0.15)
				)
				(justify left bottom)
				(hide yes)
			)
		)
		(property "Val" "47n"
			(at 97.155 178.435 90)
			(effects
				(font
					(size 1.27 1.27)
					(thickness 0.15)
				)
				(justify right)
			)
		)
		(property "License" "Apache-2.0"
			(at 119.38 194.31 0)
			(effects
				(font
					(size 1.27 1.27)
					(thickness 0.15)
				)
				(justify left bottom)
				(hide yes)
			)
		)
		(property "Author" "Antmicro"
			(at 121.92 194.31 0)
			(effects
				(font
					(size 1.27 1.27)
					(thickness 0.15)
				)
				(justify left bottom)
				(hide yes)
			)
		)
		(property "Voltage" ""
			(at 124.46 194.31 0)
			(effects
				(font
					(size 1.27 1.27)
				)
				(justify left bottom)
				(hide yes)
			)
		)
		(property "Dielectric" ""
			(at 127 194.31 0)
			(effects
				(font
					(size 1.27 1.27)
				)
				(justify left bottom)
				(hide yes)
			)
		)
		(pin "1"
		)
		(pin "2"
		)
		(instances
			(project "sdi-mipi-video-converter"
				(path ""
					(reference "C55")
					(unit 1)
				)
			)
		)
	)
	(symbol
		(lib_id "antmicropower:GND")
		(at 370.84 100.33 0)
		(unit 1)
		(exclude_from_sim no)
		(in_bom yes)
		(on_board yes)
		(dnp no)
		(fields_autoplaced yes)
		(property "Reference" "#PWR0147"
			(at 379.73 102.87 0)
			(effects
				(font
					(size 1.27 1.27)
					(thickness 0.15)
				)
				(justify left bottom)
				(hide yes)
			)
		)
		(property "Value" "GND"
			(at 370.84 105.41 0)
			(effects
				(font
					(size 1.27 1.27)
					(thickness 0.15)
				)
			)
		)
		(property "Footprint" ""
			(at 379.73 107.95 0)
			(effects
				(font
					(size 1.27 1.27)
					(thickness 0.15)
				)
				(justify left bottom)
				(hide yes)
			)
		)
		(property "Datasheet" ""
			(at 379.73 113.03 0)
			(effects
				(font
					(size 1.27 1.27)
					(thickness 0.15)
				)
				(justify left bottom)
				(hide yes)
			)
		)
		(property "Description" ""
			(at 370.84 100.33 0)
			(effects
				(font
					(size 1.27 1.27)
				)
				(hide yes)
			)
		)
		(property "Author" "Antmicro"
			(at 379.73 107.95 0)
			(effects
				(font
					(size 1.27 1.27)
					(thickness 0.15)
				)
				(justify left bottom)
				(hide yes)
			)
		)
		(property "License" "Apache-2.0"
			(at 379.73 110.49 0)
			(effects
				(font
					(size 1.27 1.27)
					(thickness 0.15)
				)
				(justify left bottom)
				(hide yes)
			)
		)
		(pin "1"
		)
		(instances
			(project "sdi-mipi-video-converter"
				(path ""
					(reference "#PWR0147")
					(unit 1)
				)
			)
		)
	)
	(symbol
		(lib_id "antmicroTestPoints:TP_0.75mm_SMD")
		(at 292.1 97.79 270)
		(unit 1)
		(exclude_from_sim no)
		(in_bom yes)
		(on_board yes)
		(dnp no)
		(fields_autoplaced yes)
		(property "Reference" "TP14"
			(at 294.64 100.9649 90)
			(effects
				(font
					(size 1.27 1.27)
					(thickness 0.15)
				)
				(justify left)
			)
		)
		(property "Value" "TP_0.75mm_SMD"
			(at 284.48 115.57 0)
			(effects
				(font
					(size 1.27 1.27)
					(thickness 0.15)
				)
				(justify left bottom)
				(hide yes)
			)
		)
		(property "Footprint" "antmicro-footprints:TP_SMD_0.75mm"
			(at 281.94 115.57 0)
			(effects
				(font
					(size 1.27 1.27)
					(thickness 0.15)
				)
				(justify left bottom)
				(hide yes)
			)
		)
		(property "Datasheet" ""
			(at 279.4 115.57 0)
			(effects
				(font
					(size 1.27 1.27)
					(thickness 0.15)
				)
				(justify left bottom)
				(hide yes)
			)
		)
		(property "Description" "SMT test point"
			(at 292.1 97.79 0)
			(effects
				(font
					(size 1.27 1.27)
				)
				(hide yes)
			)
		)
		(property "MPN" ""
			(at 276.86 115.57 0)
			(effects
				(font
					(size 1.27 1.27)
					(thickness 0.15)
				)
				(justify left bottom)
				(hide yes)
			)
		)
		(property "Manufacturer" ""
			(at 274.32 115.57 0)
			(effects
				(font
					(size 1.27 1.27)
					(thickness 0.15)
				)
				(justify left bottom)
				(hide yes)
			)
		)
		(property "Author" "Antmicro"
			(at 271.78 115.57 0)
			(effects
				(font
					(size 1.27 1.27)
					(thickness 0.15)
				)
				(justify left bottom)
				(hide yes)
			)
		)
		(property "License" "Apache-2.0"
			(at 269.24 115.57 0)
			(effects
				(font
					(size 1.27 1.27)
					(thickness 0.15)
				)
				(justify left bottom)
				(hide yes)
			)
		)
		(pin "1"
		)
		(instances
			(project "sdi-mipi-video-converter"
				(path ""
					(reference "TP14")
					(unit 1)
				)
			)
		)
	)
	(symbol
		(lib_id "antmicroCapacitors0402:C_33p_0402")
		(at 64.77 172.72 180)
		(unit 1)
		(exclude_from_sim no)
		(in_bom yes)
		(on_board yes)
		(dnp no)
		(property "Reference" "C51"
			(at 62.23 175.895 0)
			(effects
				(font
					(size 1.27 1.27)
					(thickness 0.15)
				)
			)
		)
		(property "Value" "C_33p_0402"
			(at 44.45 162.56 0)
			(effects
				(font
					(size 1.27 1.27)
					(thickness 0.15)
				)
				(justify left bottom)
				(hide yes)
			)
		)
		(property "Footprint" "antmicro-footprints:C_0402_1005Metric"
			(at 44.45 160.02 0)
			(effects
				(font
					(size 1.27 1.27)
					(thickness 0.15)
				)
				(justify left bottom)
				(hide yes)
			)
		)
		(property "Datasheet" "https://spicat.kyocera-avx.com/product/mlcc/chartview/04025A330FAT2A/"
			(at 44.45 157.48 0)
			(effects
				(font
					(size 1.27 1.27)
					(thickness 0.15)
				)
				(justify left bottom)
				(hide yes)
			)
		)
		(property "Description" "SMD Multilayer Ceramic Capacitor, 33 pF, 50 V, 0402 [1005 Metric], ± 5%, C0G / NP0, MC"
			(at 64.77 172.72 0)
			(effects
				(font
					(size 1.27 1.27)
				)
				(hide yes)
			)
		)
		(property "Manufacturer" "KYOCERA AVX"
			(at 44.45 152.4 0)
			(effects
				(font
					(size 1.27 1.27)
					(thickness 0.15)
				)
				(justify left bottom)
				(hide yes)
			)
		)
		(property "MPN" "04025A330FAT2A"
			(at 44.45 154.94 0)
			(effects
				(font
					(size 1.27 1.27)
					(thickness 0.15)
				)
				(justify left bottom)
				(hide yes)
			)
		)
		(property "Val" "33p"
			(at 62.23 178.435 0)
			(effects
				(font
					(size 1.27 1.27)
					(thickness 0.15)
				)
			)
		)
		(property "License" "Apache-2.0"
			(at 44.45 149.86 0)
			(effects
				(font
					(size 1.27 1.27)
					(thickness 0.15)
				)
				(justify left bottom)
				(hide yes)
			)
		)
		(property "Author" "Antmicro"
			(at 44.45 147.32 0)
			(effects
				(font
					(size 1.27 1.27)
					(thickness 0.15)
				)
				(justify left bottom)
				(hide yes)
			)
		)
		(property "Voltage" ""
			(at 44.45 144.78 0)
			(effects
				(font
					(size 1.27 1.27)
				)
				(justify left bottom)
				(hide yes)
			)
		)
		(property "Dielectric" ""
			(at 44.45 142.24 0)
			(effects
				(font
					(size 1.27 1.27)
				)
				(justify left bottom)
				(hide yes)
			)
		)
		(pin "1"
		)
		(pin "2"
		)
		(instances
			(project "sdi-mipi-video-converter"
				(path ""
					(reference "C51")
					(unit 1)
				)
			)
		)
	)
	(symbol
		(lib_id "antmicropower:GND")
		(at 259.08 218.44 0)
		(unit 1)
		(exclude_from_sim no)
		(in_bom yes)
		(on_board yes)
		(dnp no)
		(fields_autoplaced yes)
		(property "Reference" "#PWR0131"
			(at 267.97 220.98 0)
			(effects
				(font
					(size 1.27 1.27)
					(thickness 0.15)
				)
				(justify left bottom)
				(hide yes)
			)
		)
		(property "Value" "GND"
			(at 259.08 223.52 0)
			(effects
				(font
					(size 1.27 1.27)
					(thickness 0.15)
				)
			)
		)
		(property "Footprint" ""
			(at 267.97 226.06 0)
			(effects
				(font
					(size 1.27 1.27)
					(thickness 0.15)
				)
				(justify left bottom)
				(hide yes)
			)
		)
		(property "Datasheet" ""
			(at 267.97 231.14 0)
			(effects
				(font
					(size 1.27 1.27)
					(thickness 0.15)
				)
				(justify left bottom)
				(hide yes)
			)
		)
		(property "Description" ""
			(at 259.08 218.44 0)
			(effects
				(font
					(size 1.27 1.27)
				)
				(hide yes)
			)
		)
		(property "Author" "Antmicro"
			(at 267.97 226.06 0)
			(effects
				(font
					(size 1.27 1.27)
					(thickness 0.15)
				)
				(justify left bottom)
				(hide yes)
			)
		)
		(property "License" "Apache-2.0"
			(at 267.97 228.6 0)
			(effects
				(font
					(size 1.27 1.27)
					(thickness 0.15)
				)
				(justify left bottom)
				(hide yes)
			)
		)
		(pin "1"
		)
		(instances
			(project "sdi-mipi-video-converter"
				(path ""
					(reference "#PWR0131")
					(unit 1)
				)
			)
		)
	)
	(symbol
		(lib_id "antmicroResistors0603:R_200R_0603")
		(at 162.56 248.92 90)
		(unit 1)
		(exclude_from_sim no)
		(in_bom yes)
		(on_board yes)
		(dnp no)
		(fields_autoplaced yes)
		(property "Reference" "R101"
			(at 165.1 245.1099 90)
			(effects
				(font
					(size 1.27 1.27)
					(thickness 0.15)
				)
				(justify right)
			)
		)
		(property "Value" "R_200R_0603"
			(at 175.26 228.6 0)
			(effects
				(font
					(size 1.27 1.27)
					(thickness 0.15)
				)
				(justify left bottom)
				(hide yes)
			)
		)
		(property "Footprint" "antmicro-footprints:R_0603_1608Metric"
			(at 177.8 228.6 0)
			(effects
				(font
					(size 1.27 1.27)
					(thickness 0.15)
				)
				(justify left bottom)
				(hide yes)
			)
		)
		(property "Datasheet" "https://www.bourns.com/docs/product-datasheets/cr.pdf"
			(at 180.34 228.6 0)
			(effects
				(font
					(size 1.27 1.27)
					(thickness 0.15)
				)
				(justify left bottom)
				(hide yes)
			)
		)
		(property "Description" "SMD Chip Resistor, 200 ohm, ± 1%, 100 mW, 0603 [1608 Metric], Thick Film, General Purpose"
			(at 162.56 248.92 0)
			(effects
				(font
					(size 1.27 1.27)
				)
				(hide yes)
			)
		)
		(property "Manufacturer" "Bourns"
			(at 185.42 228.6 0)
			(effects
				(font
					(size 1.27 1.27)
					(thickness 0.15)
				)
				(justify left bottom)
				(hide yes)
			)
		)
		(property "MPN" "CR0603-FX-2000ELF"
			(at 182.88 228.6 0)
			(effects
				(font
					(size 1.27 1.27)
					(thickness 0.15)
				)
				(justify left bottom)
				(hide yes)
			)
		)
		(property "Val" "200R"
			(at 165.1 247.6499 90)
			(effects
				(font
					(size 1.27 1.27)
					(thickness 0.15)
				)
				(justify right)
			)
		)
		(property "License" "Apache-2.0"
			(at 187.96 228.6 0)
			(effects
				(font
					(size 1.27 1.27)
					(thickness 0.15)
				)
				(justify left bottom)
				(hide yes)
			)
		)
		(property "Author" "Antmicro"
			(at 190.5 228.6 0)
			(effects
				(font
					(size 1.27 1.27)
					(thickness 0.15)
				)
				(justify left bottom)
				(hide yes)
			)
		)
		(property "Tolerance" "1%"
			(at 172.72 228.6 0)
			(effects
				(font
					(size 1.27 1.27)
				)
				(justify left bottom)
				(hide yes)
			)
		)
		(pin "1"
		)
		(pin "2"
		)
		(instances
			(project "sdi-mipi-video-converter"
				(path ""
					(reference "R101")
					(unit 1)
				)
			)
		)
	)
	(symbol
		(lib_id "antmicropower:GND")
		(at 247.65 257.81 0)
		(unit 1)
		(exclude_from_sim no)
		(in_bom yes)
		(on_board yes)
		(dnp no)
		(fields_autoplaced yes)
		(property "Reference" "#PWR0127"
			(at 256.54 260.35 0)
			(effects
				(font
					(size 1.27 1.27)
					(thickness 0.15)
				)
				(justify left bottom)
				(hide yes)
			)
		)
		(property "Value" "GND"
			(at 247.65 262.89 0)
			(effects
				(font
					(size 1.27 1.27)
					(thickness 0.15)
				)
			)
		)
		(property "Footprint" ""
			(at 256.54 265.43 0)
			(effects
				(font
					(size 1.27 1.27)
					(thickness 0.15)
				)
				(justify left bottom)
				(hide yes)
			)
		)
		(property "Datasheet" ""
			(at 256.54 270.51 0)
			(effects
				(font
					(size 1.27 1.27)
					(thickness 0.15)
				)
				(justify left bottom)
				(hide yes)
			)
		)
		(property "Description" ""
			(at 247.65 257.81 0)
			(effects
				(font
					(size 1.27 1.27)
				)
				(hide yes)
			)
		)
		(property "Author" "Antmicro"
			(at 256.54 265.43 0)
			(effects
				(font
					(size 1.27 1.27)
					(thickness 0.15)
				)
				(justify left bottom)
				(hide yes)
			)
		)
		(property "License" "Apache-2.0"
			(at 256.54 267.97 0)
			(effects
				(font
					(size 1.27 1.27)
					(thickness 0.15)
				)
				(justify left bottom)
				(hide yes)
			)
		)
		(pin "1"
		)
		(instances
			(project "sdi-mipi-video-converter"
				(path ""
					(reference "#PWR0127")
					(unit 1)
				)
			)
		)
	)
	(symbol
		(lib_id "antmicroCapacitors0402:C_1u_0402")
		(at 88.9 204.47 0)
		(mirror y)
		(unit 1)
		(exclude_from_sim no)
		(in_bom yes)
		(on_board yes)
		(dnp no)
		(fields_autoplaced yes)
		(property "Reference" "C54"
			(at 86.3536 208.28 0)
			(effects
				(font
					(size 1.27 1.27)
					(thickness 0.15)
				)
			)
		)
		(property "Value" "C_1u_0402"
			(at 68.58 214.63 0)
			(effects
				(font
					(size 1.27 1.27)
					(thickness 0.15)
				)
				(justify left bottom)
				(hide yes)
			)
		)
		(property "Footprint" "antmicro-footprints:C_0402_1005Metric"
			(at 68.58 217.17 0)
			(effects
				(font
					(size 1.27 1.27)
					(thickness 0.15)
				)
				(justify left bottom)
				(hide yes)
			)
		)
		(property "Datasheet" "https://product.tdk.com/en/search/capacitor/ceramic/mlcc/info?part_no=C1005X6S1A105K050BC"
			(at 68.58 219.71 0)
			(effects
				(font
					(size 1.27 1.27)
					(thickness 0.15)
				)
				(justify left bottom)
				(hide yes)
			)
		)
		(property "Description" "SMD Multilayer Ceramic Capacitor, 1 µF, 10 V, 0402 [1005 Metric], ± 10%, X6S, C"
			(at 88.9 204.47 0)
			(effects
				(font
					(size 1.27 1.27)
				)
				(hide yes)
			)
		)
		(property "Manufacturer" "TDK"
			(at 68.58 224.79 0)
			(effects
				(font
					(size 1.27 1.27)
					(thickness 0.15)
				)
				(justify left bottom)
				(hide yes)
			)
		)
		(property "MPN" "C1005X6S1A105K050BC"
			(at 68.58 222.25 0)
			(effects
				(font
					(size 1.27 1.27)
					(thickness 0.15)
				)
				(justify left bottom)
				(hide yes)
			)
		)
		(property "Val" "1u"
			(at 86.3536 210.82 0)
			(effects
				(font
					(size 1.27 1.27)
					(thickness 0.15)
				)
			)
		)
		(property "License" "Apache-2.0"
			(at 68.58 227.33 0)
			(effects
				(font
					(size 1.27 1.27)
					(thickness 0.15)
				)
				(justify left bottom)
				(hide yes)
			)
		)
		(property "Author" "Antmicro"
			(at 68.58 229.87 0)
			(effects
				(font
					(size 1.27 1.27)
					(thickness 0.15)
				)
				(justify left bottom)
				(hide yes)
			)
		)
		(property "Voltage" ""
			(at 68.58 232.41 0)
			(effects
				(font
					(size 1.27 1.27)
				)
				(justify left bottom)
				(hide yes)
			)
		)
		(property "Dielectric" ""
			(at 68.58 234.95 0)
			(effects
				(font
					(size 1.27 1.27)
				)
				(justify left bottom)
				(hide yes)
			)
		)
		(pin "1"
		)
		(pin "2"
		)
		(instances
			(project "sdi-mipi-video-converter"
				(path ""
					(reference "C54")
					(unit 1)
				)
			)
		)
	)
	(symbol
		(lib_id "antmicropower:GND")
		(at 247.65 238.76 0)
		(unit 1)
		(exclude_from_sim no)
		(in_bom yes)
		(on_board yes)
		(dnp no)
		(fields_autoplaced yes)
		(property "Reference" "#PWR0126"
			(at 256.54 241.3 0)
			(effects
				(font
					(size 1.27 1.27)
					(thickness 0.15)
				)
				(justify left bottom)
				(hide yes)
			)
		)
		(property "Value" "GND"
			(at 247.65 243.84 0)
			(effects
				(font
					(size 1.27 1.27)
					(thickness 0.15)
				)
			)
		)
		(property "Footprint" ""
			(at 256.54 246.38 0)
			(effects
				(font
					(size 1.27 1.27)
					(thickness 0.15)
				)
				(justify left bottom)
				(hide yes)
			)
		)
		(property "Datasheet" ""
			(at 256.54 251.46 0)
			(effects
				(font
					(size 1.27 1.27)
					(thickness 0.15)
				)
				(justify left bottom)
				(hide yes)
			)
		)
		(property "Description" ""
			(at 247.65 238.76 0)
			(effects
				(font
					(size 1.27 1.27)
				)
				(hide yes)
			)
		)
		(property "Author" "Antmicro"
			(at 256.54 246.38 0)
			(effects
				(font
					(size 1.27 1.27)
					(thickness 0.15)
				)
				(justify left bottom)
				(hide yes)
			)
		)
		(property "License" "Apache-2.0"
			(at 256.54 248.92 0)
			(effects
				(font
					(size 1.27 1.27)
					(thickness 0.15)
				)
				(justify left bottom)
				(hide yes)
			)
		)
		(pin "1"
		)
		(instances
			(project "sdi-mipi-video-converter"
				(path ""
					(reference "#PWR0126")
					(unit 1)
				)
			)
		)
	)
	(symbol
		(lib_id "antmicropower:GND")
		(at 270.51 193.04 0)
		(unit 1)
		(exclude_from_sim no)
		(in_bom yes)
		(on_board yes)
		(dnp no)
		(fields_autoplaced yes)
		(property "Reference" "#PWR0136"
			(at 279.4 195.58 0)
			(effects
				(font
					(size 1.27 1.27)
					(thickness 0.15)
				)
				(justify left bottom)
				(hide yes)
			)
		)
		(property "Value" "GND"
			(at 273.05 194.3099 0)
			(effects
				(font
					(size 1.27 1.27)
					(thickness 0.15)
				)
				(justify left)
			)
		)
		(property "Footprint" ""
			(at 279.4 200.66 0)
			(effects
				(font
					(size 1.27 1.27)
					(thickness 0.15)
				)
				(justify left bottom)
				(hide yes)
			)
		)
		(property "Datasheet" ""
			(at 279.4 205.74 0)
			(effects
				(font
					(size 1.27 1.27)
					(thickness 0.15)
				)
				(justify left bottom)
				(hide yes)
			)
		)
		(property "Description" ""
			(at 270.51 193.04 0)
			(effects
				(font
					(size 1.27 1.27)
				)
				(hide yes)
			)
		)
		(property "Author" "Antmicro"
			(at 279.4 200.66 0)
			(effects
				(font
					(size 1.27 1.27)
					(thickness 0.15)
				)
				(justify left bottom)
				(hide yes)
			)
		)
		(property "License" "Apache-2.0"
			(at 279.4 203.2 0)
			(effects
				(font
					(size 1.27 1.27)
					(thickness 0.15)
				)
				(justify left bottom)
				(hide yes)
			)
		)
		(pin "1"
		)
		(instances
			(project "sdi-mipi-video-converter"
				(path ""
					(reference "#PWR0136")
					(unit 1)
				)
			)
		)
	)
	(symbol
		(lib_id "antmicroCapacitors0402:C_4u7_0402")
		(at 321.31 69.85 0)
		(mirror x)
		(unit 1)
		(exclude_from_sim no)
		(in_bom yes)
		(on_board yes)
		(dnp no)
		(fields_autoplaced yes)
		(property "Reference" "C77"
			(at 323.8563 63.5 0)
			(effects
				(font
					(size 1.27 1.27)
					(thickness 0.15)
				)
			)
		)
		(property "Value" "C_4u7_0402"
			(at 341.63 59.69 0)
			(effects
				(font
					(size 1.27 1.27)
					(thickness 0.15)
				)
				(justify left bottom)
				(hide yes)
			)
		)
		(property "Footprint" "antmicro-footprints:C_0402_1005Metric"
			(at 341.63 57.15 0)
			(effects
				(font
					(size 1.27 1.27)
					(thickness 0.15)
				)
				(justify left bottom)
				(hide yes)
			)
		)
		(property "Datasheet" "https://www.murata.com/products/productdetail?partno=GRM155R61A475MEAA%23"
			(at 341.63 54.61 0)
			(effects
				(font
					(size 1.27 1.27)
					(thickness 0.15)
				)
				(justify left bottom)
				(hide yes)
			)
		)
		(property "Description" "SMD Multilayer Ceramic Capacitor, 4.7 µF, 10 V, 0402 [1005 Metric], ± 20%, X5R, GRM Series"
			(at 321.31 69.85 0)
			(effects
				(font
					(size 1.27 1.27)
				)
				(hide yes)
			)
		)
		(property "Manufacturer" "Murata"
			(at 341.63 49.53 0)
			(effects
				(font
					(size 1.27 1.27)
					(thickness 0.15)
				)
				(justify left bottom)
				(hide yes)
			)
		)
		(property "MPN" "GRM155R61A475MEAAD"
			(at 341.63 52.07 0)
			(effects
				(font
					(size 1.27 1.27)
					(thickness 0.15)
				)
				(justify left bottom)
				(hide yes)
			)
		)
		(property "Val" "4u7"
			(at 323.8563 66.04 0)
			(effects
				(font
					(size 1.27 1.27)
					(thickness 0.15)
				)
			)
		)
		(property "License" "Apache-2.0"
			(at 341.63 46.99 0)
			(effects
				(font
					(size 1.27 1.27)
					(thickness 0.15)
				)
				(justify left bottom)
				(hide yes)
			)
		)
		(property "Author" "Antmicro"
			(at 341.63 44.45 0)
			(effects
				(font
					(size 1.27 1.27)
					(thickness 0.15)
				)
				(justify left bottom)
				(hide yes)
			)
		)
		(property "Voltage" ""
			(at 341.63 41.91 0)
			(effects
				(font
					(size 1.27 1.27)
				)
				(justify left bottom)
				(hide yes)
			)
		)
		(property "Dielectric" ""
			(at 341.63 39.37 0)
			(effects
				(font
					(size 1.27 1.27)
				)
				(justify left bottom)
				(hide yes)
			)
		)
		(pin "1"
		)
		(pin "2"
		)
		(instances
			(project "sdi-mipi-video-converter"
				(path ""
					(reference "C77")
					(unit 1)
				)
			)
		)
	)
	(symbol
		(lib_id "antmicroCapacitors0402:C_100n_0402")
		(at 270.51 256.54 90)
		(unit 1)
		(exclude_from_sim no)
		(in_bom yes)
		(on_board yes)
		(dnp no)
		(fields_autoplaced yes)
		(property "Reference" "C74"
			(at 273.05 252.7235 90)
			(effects
				(font
					(size 1.27 1.27)
					(thickness 0.15)
				)
				(justify right)
			)
		)
		(property "Value" "C_100n_0402"
			(at 280.67 236.22 0)
			(effects
				(font
					(size 1.27 1.27)
					(thickness 0.15)
				)
				(justify left bottom)
				(hide yes)
			)
		)
		(property "Footprint" "antmicro-footprints:C_0402_1005Metric"
			(at 283.21 236.22 0)
			(effects
				(font
					(size 1.27 1.27)
					(thickness 0.15)
				)
				(justify left bottom)
				(hide yes)
			)
		)
		(property "Datasheet" "https://www.murata.com/products/productdetail?partno=GRM155R61H104KE14%23"
			(at 285.75 236.22 0)
			(effects
				(font
					(size 1.27 1.27)
					(thickness 0.15)
				)
				(justify left bottom)
				(hide yes)
			)
		)
		(property "Description" "SMD Multilayer Ceramic Capacitor, 0.1 µF, 50 V, 0402 [1005 Metric], ± 10%, X5R, GRM Series"
			(at 270.51 256.54 0)
			(effects
				(font
					(size 1.27 1.27)
				)
				(hide yes)
			)
		)
		(property "Manufacturer" "Murata"
			(at 290.83 236.22 0)
			(effects
				(font
					(size 1.27 1.27)
					(thickness 0.15)
				)
				(justify left bottom)
				(hide yes)
			)
		)
		(property "MPN" "GRM155R61H104KE14D"
			(at 288.29 236.22 0)
			(effects
				(font
					(size 1.27 1.27)
					(thickness 0.15)
				)
				(justify left bottom)
				(hide yes)
			)
		)
		(property "Val" "100n"
			(at 273.05 255.2635 90)
			(effects
				(font
					(size 1.27 1.27)
					(thickness 0.15)
				)
				(justify right)
			)
		)
		(property "License" "Apache-2.0"
			(at 293.37 236.22 0)
			(effects
				(font
					(size 1.27 1.27)
					(thickness 0.15)
				)
				(justify left bottom)
				(hide yes)
			)
		)
		(property "Author" "Antmicro"
			(at 295.91 236.22 0)
			(effects
				(font
					(size 1.27 1.27)
					(thickness 0.15)
				)
				(justify left bottom)
				(hide yes)
			)
		)
		(property "Voltage" "50V"
			(at 298.45 236.22 0)
			(effects
				(font
					(size 1.27 1.27)
				)
				(justify left bottom)
				(hide yes)
			)
		)
		(property "Dielectric" "X5R"
			(at 300.99 236.22 0)
			(effects
				(font
					(size 1.27 1.27)
				)
				(justify left bottom)
				(hide yes)
			)
		)
		(pin "1"
		)
		(pin "2"
		)
		(instances
			(project "sdi-mipi-video-converter"
				(path ""
					(reference "C74")
					(unit 1)
				)
			)
		)
	)
	(symbol
		(lib_id "antmicroTestPoints:TP_0.75mm_SMD")
		(at 168.91 190.5 0)
		(unit 1)
		(exclude_from_sim no)
		(in_bom yes)
		(on_board yes)
		(dnp no)
		(fields_autoplaced yes)
		(property "Reference" "TP37"
			(at 173.99 190.4999 0)
			(effects
				(font
					(size 1.27 1.27)
					(thickness 0.15)
				)
				(justify left)
			)
		)
		(property "Value" "TP_0.75mm_SMD"
			(at 186.69 198.12 0)
			(effects
				(font
					(size 1.27 1.27)
					(thickness 0.15)
				)
				(justify left bottom)
				(hide yes)
			)
		)
		(property "Footprint" "antmicro-footprints:TP_SMD_0.75mm"
			(at 186.69 200.66 0)
			(effects
				(font
					(size 1.27 1.27)
					(thickness 0.15)
				)
				(justify left bottom)
				(hide yes)
			)
		)
		(property "Datasheet" ""
			(at 186.69 203.2 0)
			(effects
				(font
					(size 1.27 1.27)
					(thickness 0.15)
				)
				(justify left bottom)
				(hide yes)
			)
		)
		(property "Description" "SMT test point"
			(at 168.91 190.5 0)
			(effects
				(font
					(size 1.27 1.27)
				)
				(hide yes)
			)
		)
		(property "MPN" ""
			(at 186.69 205.74 0)
			(effects
				(font
					(size 1.27 1.27)
					(thickness 0.15)
				)
				(justify left bottom)
				(hide yes)
			)
		)
		(property "Manufacturer" ""
			(at 186.69 208.28 0)
			(effects
				(font
					(size 1.27 1.27)
					(thickness 0.15)
				)
				(justify left bottom)
				(hide yes)
			)
		)
		(property "Author" "Antmicro"
			(at 186.69 210.82 0)
			(effects
				(font
					(size 1.27 1.27)
					(thickness 0.15)
				)
				(justify left bottom)
				(hide yes)
			)
		)
		(property "License" "Apache-2.0"
			(at 186.69 213.36 0)
			(effects
				(font
					(size 1.27 1.27)
					(thickness 0.15)
				)
				(justify left bottom)
				(hide yes)
			)
		)
		(pin "1"
		)
		(instances
			(project "sdi-mipi-video-converter"
				(path ""
					(reference "TP37")
					(unit 1)
				)
			)
		)
	)
	(symbol
		(lib_id "antmicroTestPoints:TP_0.75mm_SMD")
		(at 168.91 167.64 0)
		(unit 1)
		(exclude_from_sim no)
		(in_bom yes)
		(on_board yes)
		(dnp no)
		(fields_autoplaced yes)
		(property "Reference" "TP28"
			(at 173.99 167.6399 0)
			(effects
				(font
					(size 1.27 1.27)
					(thickness 0.15)
				)
				(justify left)
			)
		)
		(property "Value" "TP_0.75mm_SMD"
			(at 186.69 175.26 0)
			(effects
				(font
					(size 1.27 1.27)
					(thickness 0.15)
				)
				(justify left bottom)
				(hide yes)
			)
		)
		(property "Footprint" "antmicro-footprints:TP_SMD_0.75mm"
			(at 186.69 177.8 0)
			(effects
				(font
					(size 1.27 1.27)
					(thickness 0.15)
				)
				(justify left bottom)
				(hide yes)
			)
		)
		(property "Datasheet" ""
			(at 186.69 180.34 0)
			(effects
				(font
					(size 1.27 1.27)
					(thickness 0.15)
				)
				(justify left bottom)
				(hide yes)
			)
		)
		(property "Description" "SMT test point"
			(at 168.91 167.64 0)
			(effects
				(font
					(size 1.27 1.27)
				)
				(hide yes)
			)
		)
		(property "MPN" ""
			(at 186.69 182.88 0)
			(effects
				(font
					(size 1.27 1.27)
					(thickness 0.15)
				)
				(justify left bottom)
				(hide yes)
			)
		)
		(property "Manufacturer" ""
			(at 186.69 185.42 0)
			(effects
				(font
					(size 1.27 1.27)
					(thickness 0.15)
				)
				(justify left bottom)
				(hide yes)
			)
		)
		(property "Author" "Antmicro"
			(at 186.69 187.96 0)
			(effects
				(font
					(size 1.27 1.27)
					(thickness 0.15)
				)
				(justify left bottom)
				(hide yes)
			)
		)
		(property "License" "Apache-2.0"
			(at 186.69 190.5 0)
			(effects
				(font
					(size 1.27 1.27)
					(thickness 0.15)
				)
				(justify left bottom)
				(hide yes)
			)
		)
		(pin "1"
		)
		(instances
			(project "sdi-mipi-video-converter"
				(path ""
					(reference "TP28")
					(unit 1)
				)
			)
		)
	)
	(symbol
		(lib_id "antmicropower:+3.3V")
		(at 247.65 209.55 0)
		(unit 1)
		(exclude_from_sim no)
		(in_bom yes)
		(on_board yes)
		(dnp no)
		(fields_autoplaced yes)
		(property "Reference" "#PWR0123"
			(at 247.65 213.36 0)
			(effects
				(font
					(size 1.27 1.27)
				)
				(hide yes)
			)
		)
		(property "Value" "+3V3"
			(at 247.65 204.47 0)
			(effects
				(font
					(size 1.27 1.27)
				)
			)
		)
		(property "Footprint" ""
			(at 247.65 209.55 0)
			(effects
				(font
					(size 1.27 1.27)
				)
				(hide yes)
			)
		)
		(property "Datasheet" ""
			(at 247.65 209.55 0)
			(effects
				(font
					(size 1.27 1.27)
				)
				(hide yes)
			)
		)
		(property "Description" ""
			(at 247.65 209.55 0)
			(effects
				(font
					(size 1.27 1.27)
				)
				(hide yes)
			)
		)
		(pin "1"
		)
		(instances
			(project "sdi-mipi-video-converter"
				(path ""
					(reference "#PWR0123")
					(unit 1)
				)
			)
		)
	)
	(symbol
		(lib_id "antmicropower:+3.3V")
		(at 118.11 20.32 0)
		(unit 1)
		(exclude_from_sim no)
		(in_bom yes)
		(on_board yes)
		(dnp no)
		(fields_autoplaced yes)
		(property "Reference" "#PWR0116"
			(at 118.11 24.13 0)
			(effects
				(font
					(size 1.27 1.27)
				)
				(hide yes)
			)
		)
		(property "Value" "+3V3"
			(at 118.11 15.24 0)
			(effects
				(font
					(size 1.27 1.27)
				)
			)
		)
		(property "Footprint" ""
			(at 118.11 20.32 0)
			(effects
				(font
					(size 1.27 1.27)
				)
				(hide yes)
			)
		)
		(property "Datasheet" ""
			(at 118.11 20.32 0)
			(effects
				(font
					(size 1.27 1.27)
				)
				(hide yes)
			)
		)
		(property "Description" ""
			(at 118.11 20.32 0)
			(effects
				(font
					(size 1.27 1.27)
				)
				(hide yes)
			)
		)
		(pin "1"
		)
		(instances
			(project "sdi-mipi-video-converter"
				(path ""
					(reference "#PWR0116")
					(unit 1)
				)
			)
		)
	)
	(symbol
		(lib_id "antmicroTestPoints:TP_0.75mm_SMD")
		(at 132.08 229.87 0)
		(unit 1)
		(exclude_from_sim no)
		(in_bom yes)
		(on_board yes)
		(dnp no)
		(fields_autoplaced yes)
		(property "Reference" "TP24"
			(at 137.16 229.8699 0)
			(effects
				(font
					(size 1.27 1.27)
					(thickness 0.15)
				)
				(justify left)
			)
		)
		(property "Value" "TP_0.75mm_SMD"
			(at 149.86 237.49 0)
			(effects
				(font
					(size 1.27 1.27)
					(thickness 0.15)
				)
				(justify left bottom)
				(hide yes)
			)
		)
		(property "Footprint" "antmicro-footprints:TP_SMD_0.75mm"
			(at 149.86 240.03 0)
			(effects
				(font
					(size 1.27 1.27)
					(thickness 0.15)
				)
				(justify left bottom)
				(hide yes)
			)
		)
		(property "Datasheet" ""
			(at 149.86 242.57 0)
			(effects
				(font
					(size 1.27 1.27)
					(thickness 0.15)
				)
				(justify left bottom)
				(hide yes)
			)
		)
		(property "Description" "SMT test point"
			(at 132.08 229.87 0)
			(effects
				(font
					(size 1.27 1.27)
				)
				(hide yes)
			)
		)
		(property "MPN" ""
			(at 149.86 245.11 0)
			(effects
				(font
					(size 1.27 1.27)
					(thickness 0.15)
				)
				(justify left bottom)
				(hide yes)
			)
		)
		(property "Manufacturer" ""
			(at 149.86 247.65 0)
			(effects
				(font
					(size 1.27 1.27)
					(thickness 0.15)
				)
				(justify left bottom)
				(hide yes)
			)
		)
		(property "Author" "Antmicro"
			(at 149.86 250.19 0)
			(effects
				(font
					(size 1.27 1.27)
					(thickness 0.15)
				)
				(justify left bottom)
				(hide yes)
			)
		)
		(property "License" "Apache-2.0"
			(at 149.86 252.73 0)
			(effects
				(font
					(size 1.27 1.27)
					(thickness 0.15)
				)
				(justify left bottom)
				(hide yes)
			)
		)
		(pin "1"
		)
		(instances
			(project "sdi-mipi-video-converter"
				(path ""
					(reference "TP24")
					(unit 1)
				)
			)
		)
	)
	(symbol
		(lib_id "antmicropower:GND")
		(at 270.51 238.76 0)
		(unit 1)
		(exclude_from_sim no)
		(in_bom yes)
		(on_board yes)
		(dnp no)
		(fields_autoplaced yes)
		(property "Reference" "#PWR0138"
			(at 279.4 241.3 0)
			(effects
				(font
					(size 1.27 1.27)
					(thickness 0.15)
				)
				(justify left bottom)
				(hide yes)
			)
		)
		(property "Value" "GND"
			(at 267.97 240.0299 0)
			(effects
				(font
					(size 1.27 1.27)
					(thickness 0.15)
				)
				(justify right)
			)
		)
		(property "Footprint" ""
			(at 279.4 246.38 0)
			(effects
				(font
					(size 1.27 1.27)
					(thickness 0.15)
				)
				(justify left bottom)
				(hide yes)
			)
		)
		(property "Datasheet" ""
			(at 279.4 251.46 0)
			(effects
				(font
					(size 1.27 1.27)
					(thickness 0.15)
				)
				(justify left bottom)
				(hide yes)
			)
		)
		(property "Description" ""
			(at 270.51 238.76 0)
			(effects
				(font
					(size 1.27 1.27)
				)
				(hide yes)
			)
		)
		(property "Author" "Antmicro"
			(at 279.4 246.38 0)
			(effects
				(font
					(size 1.27 1.27)
					(thickness 0.15)
				)
				(justify left bottom)
				(hide yes)
			)
		)
		(property "License" "Apache-2.0"
			(at 279.4 248.92 0)
			(effects
				(font
					(size 1.27 1.27)
					(thickness 0.15)
				)
				(justify left bottom)
				(hide yes)
			)
		)
		(pin "1"
		)
		(instances
			(project "sdi-mipi-video-converter"
				(path ""
					(reference "#PWR0138")
					(unit 1)
				)
			)
		)
	)
	(symbol
		(lib_id "antmicropower:GND")
		(at 118.11 34.29 0)
		(unit 1)
		(exclude_from_sim no)
		(in_bom yes)
		(on_board yes)
		(dnp no)
		(fields_autoplaced yes)
		(property "Reference" "#PWR0117"
			(at 127 36.83 0)
			(effects
				(font
					(size 1.27 1.27)
					(thickness 0.15)
				)
				(justify left bottom)
				(hide yes)
			)
		)
		(property "Value" "GND"
			(at 118.11 39.37 0)
			(effects
				(font
					(size 1.27 1.27)
					(thickness 0.15)
				)
			)
		)
		(property "Footprint" ""
			(at 127 41.91 0)
			(effects
				(font
					(size 1.27 1.27)
					(thickness 0.15)
				)
				(justify left bottom)
				(hide yes)
			)
		)
		(property "Datasheet" ""
			(at 127 46.99 0)
			(effects
				(font
					(size 1.27 1.27)
					(thickness 0.15)
				)
				(justify left bottom)
				(hide yes)
			)
		)
		(property "Description" ""
			(at 118.11 34.29 0)
			(effects
				(font
					(size 1.27 1.27)
				)
				(hide yes)
			)
		)
		(property "Author" "Antmicro"
			(at 127 41.91 0)
			(effects
				(font
					(size 1.27 1.27)
					(thickness 0.15)
				)
				(justify left bottom)
				(hide yes)
			)
		)
		(property "License" "Apache-2.0"
			(at 127 44.45 0)
			(effects
				(font
					(size 1.27 1.27)
					(thickness 0.15)
				)
				(justify left bottom)
				(hide yes)
			)
		)
		(pin "1"
		)
		(instances
			(project "sdi-mipi-video-converter"
				(path ""
					(reference "#PWR0117")
					(unit 1)
				)
			)
		)
	)
	(symbol
		(lib_id "antmicroCapacitorsmisc:C_100n_0201")
		(at 118.11 33.02 90)
		(unit 1)
		(exclude_from_sim no)
		(in_bom yes)
		(on_board yes)
		(dnp no)
		(fields_autoplaced yes)
		(property "Reference" "C65"
			(at 120.65 29.2035 90)
			(effects
				(font
					(size 1.27 1.27)
					(thickness 0.15)
				)
				(justify right)
			)
		)
		(property "Value" "C_100n_0201"
			(at 128.27 12.7 0)
			(effects
				(font
					(size 1.27 1.27)
					(thickness 0.15)
				)
				(justify left bottom)
				(hide yes)
			)
		)
		(property "Footprint" "antmicro-footprints:C_0201"
			(at 130.81 12.7 0)
			(effects
				(font
					(size 1.27 1.27)
					(thickness 0.15)
				)
				(justify left bottom)
				(hide yes)
			)
		)
		(property "Datasheet" "https://www.yageo.com/en/Chart/Download/pdf/CC0201KRX6S5BB104"
			(at 133.35 12.7 0)
			(effects
				(font
					(size 1.27 1.27)
					(thickness 0.15)
				)
				(justify left bottom)
				(hide yes)
			)
		)
		(property "Description" "SMD Multilayer Ceramic Capacitor, 0.1 µF, 6.3 V, 0201 [0603 Metric], ± 10%, X6S, CC Series"
			(at 118.11 33.02 0)
			(effects
				(font
					(size 1.27 1.27)
				)
				(hide yes)
			)
		)
		(property "Manufacturer" "YAGEO"
			(at 138.43 12.7 0)
			(effects
				(font
					(size 1.27 1.27)
					(thickness 0.15)
				)
				(justify left bottom)
				(hide yes)
			)
		)
		(property "MPN" "CC0201KRX6S5BB104"
			(at 135.89 12.7 0)
			(effects
				(font
					(size 1.27 1.27)
					(thickness 0.15)
				)
				(justify left bottom)
				(hide yes)
			)
		)
		(property "Val" "100n"
			(at 120.65 31.7435 90)
			(effects
				(font
					(size 1.27 1.27)
					(thickness 0.15)
				)
				(justify right)
			)
		)
		(property "License" "Apache-2.0"
			(at 140.97 12.7 0)
			(effects
				(font
					(size 1.27 1.27)
					(thickness 0.15)
				)
				(justify left bottom)
				(hide yes)
			)
		)
		(property "Author" "Antmicro"
			(at 143.51 12.7 0)
			(effects
				(font
					(size 1.27 1.27)
					(thickness 0.15)
				)
				(justify left bottom)
				(hide yes)
			)
		)
		(property "Voltage" ""
			(at 146.05 12.7 0)
			(effects
				(font
					(size 1.27 1.27)
				)
				(justify left bottom)
				(hide yes)
			)
		)
		(property "Dielectric" ""
			(at 148.59 12.7 0)
			(effects
				(font
					(size 1.27 1.27)
				)
				(justify left bottom)
				(hide yes)
			)
		)
		(property "Public" "False"
			(at 151.13 12.7 0)
			(effects
				(font
					(size 1.27 1.27)
				)
				(justify left bottom)
				(hide yes)
			)
		)
		(pin "1"
		)
		(pin "2"
		)
		(instances
			(project "sdi-mipi-video-converter"
				(path ""
					(reference "C65")
					(unit 1)
				)
			)
		)
	)
	(symbol
		(lib_id "antmicroResistors0402:R_75R_0402")
		(at 326.39 93.98 0)
		(unit 1)
		(exclude_from_sim no)
		(in_bom yes)
		(on_board yes)
		(dnp no)
		(property "Reference" "R61"
			(at 333.375 92.71 0)
			(effects
				(font
					(size 1.27 1.27)
					(thickness 0.15)
				)
			)
		)
		(property "Value" "R_75R_0402"
			(at 346.71 106.68 0)
			(effects
				(font
					(size 1.27 1.27)
					(thickness 0.15)
				)
				(justify left bottom)
				(hide yes)
			)
		)
		(property "Footprint" "antmicro-footprints:R_0402_1005Metric"
			(at 346.71 109.22 0)
			(effects
				(font
					(size 1.27 1.27)
					(thickness 0.15)
				)
				(justify left bottom)
				(hide yes)
			)
		)
		(property "Datasheet" "https://www.bourns.com/docs/product-datasheets/cr.pdf"
			(at 346.71 111.76 0)
			(effects
				(font
					(size 1.27 1.27)
					(thickness 0.15)
				)
				(justify left bottom)
				(hide yes)
			)
		)
		(property "Description" "SMD Chip Resistor, 75 ohm, ± 1%, 62.5 mW, 0402 [1005 Metric], Thick Film, General Purpose"
			(at 326.39 93.98 0)
			(effects
				(font
					(size 1.27 1.27)
				)
				(hide yes)
			)
		)
		(property "Manufacturer" "Bourns"
			(at 346.71 116.84 0)
			(effects
				(font
					(size 1.27 1.27)
					(thickness 0.15)
				)
				(justify left bottom)
				(hide yes)
			)
		)
		(property "MPN" "CR0402-FX-75R0GLF"
			(at 346.71 114.3 0)
			(effects
				(font
					(size 1.27 1.27)
					(thickness 0.15)
				)
				(justify left bottom)
				(hide yes)
			)
		)
		(property "Val" "75R"
			(at 324.485 92.71 0)
			(effects
				(font
					(size 1.27 1.27)
					(thickness 0.15)
				)
			)
		)
		(property "License" "Apache-2.0"
			(at 346.71 119.38 0)
			(effects
				(font
					(size 1.27 1.27)
					(thickness 0.15)
				)
				(justify left bottom)
				(hide yes)
			)
		)
		(property "Author" "Antmicro"
			(at 346.71 121.92 0)
			(effects
				(font
					(size 1.27 1.27)
					(thickness 0.15)
				)
				(justify left bottom)
				(hide yes)
			)
		)
		(property "Tolerance" "1%"
			(at 346.71 104.14 0)
			(effects
				(font
					(size 1.27 1.27)
				)
				(justify left bottom)
				(hide yes)
			)
		)
		(pin "1"
		)
		(pin "2"
		)
		(instances
			(project "sdi-mipi-video-converter"
				(path ""
					(reference "R61")
					(unit 1)
				)
			)
		)
	)
	(symbol
		(lib_id "antmicroCapacitors0402:C_100n_0402")
		(at 259.08 256.54 90)
		(unit 1)
		(exclude_from_sim no)
		(in_bom yes)
		(on_board yes)
		(dnp no)
		(fields_autoplaced yes)
		(property "Reference" "C69"
			(at 261.62 252.7235 90)
			(effects
				(font
					(size 1.27 1.27)
					(thickness 0.15)
				)
				(justify right)
			)
		)
		(property "Value" "C_100n_0402"
			(at 269.24 236.22 0)
			(effects
				(font
					(size 1.27 1.27)
					(thickness 0.15)
				)
				(justify left bottom)
				(hide yes)
			)
		)
		(property "Footprint" "antmicro-footprints:C_0402_1005Metric"
			(at 271.78 236.22 0)
			(effects
				(font
					(size 1.27 1.27)
					(thickness 0.15)
				)
				(justify left bottom)
				(hide yes)
			)
		)
		(property "Datasheet" "https://www.murata.com/products/productdetail?partno=GRM155R61H104KE14%23"
			(at 274.32 236.22 0)
			(effects
				(font
					(size 1.27 1.27)
					(thickness 0.15)
				)
				(justify left bottom)
				(hide yes)
			)
		)
		(property "Description" "SMD Multilayer Ceramic Capacitor, 0.1 µF, 50 V, 0402 [1005 Metric], ± 10%, X5R, GRM Series"
			(at 259.08 256.54 0)
			(effects
				(font
					(size 1.27 1.27)
				)
				(hide yes)
			)
		)
		(property "Manufacturer" "Murata"
			(at 279.4 236.22 0)
			(effects
				(font
					(size 1.27 1.27)
					(thickness 0.15)
				)
				(justify left bottom)
				(hide yes)
			)
		)
		(property "MPN" "GRM155R61H104KE14D"
			(at 276.86 236.22 0)
			(effects
				(font
					(size 1.27 1.27)
					(thickness 0.15)
				)
				(justify left bottom)
				(hide yes)
			)
		)
		(property "Val" "100n"
			(at 261.62 255.2635 90)
			(effects
				(font
					(size 1.27 1.27)
					(thickness 0.15)
				)
				(justify right)
			)
		)
		(property "License" "Apache-2.0"
			(at 281.94 236.22 0)
			(effects
				(font
					(size 1.27 1.27)
					(thickness 0.15)
				)
				(justify left bottom)
				(hide yes)
			)
		)
		(property "Author" "Antmicro"
			(at 284.48 236.22 0)
			(effects
				(font
					(size 1.27 1.27)
					(thickness 0.15)
				)
				(justify left bottom)
				(hide yes)
			)
		)
		(property "Voltage" "50V"
			(at 287.02 236.22 0)
			(effects
				(font
					(size 1.27 1.27)
				)
				(justify left bottom)
				(hide yes)
			)
		)
		(property "Dielectric" "X5R"
			(at 289.56 236.22 0)
			(effects
				(font
					(size 1.27 1.27)
				)
				(justify left bottom)
				(hide yes)
			)
		)
		(pin "1"
		)
		(pin "2"
		)
		(instances
			(project "sdi-mipi-video-converter"
				(path ""
					(reference "C69")
					(unit 1)
				)
			)
		)
	)
	(symbol
		(lib_id "antmicroCapacitors0402:C_100n_0402")
		(at 259.08 217.17 90)
		(unit 1)
		(exclude_from_sim no)
		(in_bom yes)
		(on_board yes)
		(dnp no)
		(fields_autoplaced yes)
		(property "Reference" "C67"
			(at 261.62 213.3535 90)
			(effects
				(font
					(size 1.27 1.27)
					(thickness 0.15)
				)
				(justify right)
			)
		)
		(property "Value" "C_100n_0402"
			(at 269.24 196.85 0)
			(effects
				(font
					(size 1.27 1.27)
					(thickness 0.15)
				)
				(justify left bottom)
				(hide yes)
			)
		)
		(property "Footprint" "antmicro-footprints:C_0402_1005Metric"
			(at 271.78 196.85 0)
			(effects
				(font
					(size 1.27 1.27)
					(thickness 0.15)
				)
				(justify left bottom)
				(hide yes)
			)
		)
		(property "Datasheet" "https://www.murata.com/products/productdetail?partno=GRM155R61H104KE14%23"
			(at 274.32 196.85 0)
			(effects
				(font
					(size 1.27 1.27)
					(thickness 0.15)
				)
				(justify left bottom)
				(hide yes)
			)
		)
		(property "Description" "SMD Multilayer Ceramic Capacitor, 0.1 µF, 50 V, 0402 [1005 Metric], ± 10%, X5R, GRM Series"
			(at 259.08 217.17 0)
			(effects
				(font
					(size 1.27 1.27)
				)
				(hide yes)
			)
		)
		(property "Manufacturer" "Murata"
			(at 279.4 196.85 0)
			(effects
				(font
					(size 1.27 1.27)
					(thickness 0.15)
				)
				(justify left bottom)
				(hide yes)
			)
		)
		(property "MPN" "GRM155R61H104KE14D"
			(at 276.86 196.85 0)
			(effects
				(font
					(size 1.27 1.27)
					(thickness 0.15)
				)
				(justify left bottom)
				(hide yes)
			)
		)
		(property "Val" "100n"
			(at 261.62 215.8935 90)
			(effects
				(font
					(size 1.27 1.27)
					(thickness 0.15)
				)
				(justify right)
			)
		)
		(property "License" "Apache-2.0"
			(at 281.94 196.85 0)
			(effects
				(font
					(size 1.27 1.27)
					(thickness 0.15)
				)
				(justify left bottom)
				(hide yes)
			)
		)
		(property "Author" "Antmicro"
			(at 284.48 196.85 0)
			(effects
				(font
					(size 1.27 1.27)
					(thickness 0.15)
				)
				(justify left bottom)
				(hide yes)
			)
		)
		(property "Voltage" "50V"
			(at 287.02 196.85 0)
			(effects
				(font
					(size 1.27 1.27)
				)
				(justify left bottom)
				(hide yes)
			)
		)
		(property "Dielectric" "X5R"
			(at 289.56 196.85 0)
			(effects
				(font
					(size 1.27 1.27)
				)
				(justify left bottom)
				(hide yes)
			)
		)
		(pin "1"
		)
		(pin "2"
		)
		(instances
			(project "sdi-mipi-video-converter"
				(path ""
					(reference "C67")
					(unit 1)
				)
			)
		)
	)
	(symbol
		(lib_id "antmicropower:GND")
		(at 92.71 205.74 0)
		(unit 1)
		(exclude_from_sim no)
		(in_bom yes)
		(on_board yes)
		(dnp no)
		(fields_autoplaced yes)
		(property "Reference" "#PWR0112"
			(at 101.6 208.28 0)
			(effects
				(font
					(size 1.27 1.27)
					(thickness 0.15)
				)
				(justify left bottom)
				(hide yes)
			)
		)
		(property "Value" "GND"
			(at 92.71 210.82 0)
			(effects
				(font
					(size 1.27 1.27)
					(thickness 0.15)
				)
			)
		)
		(property "Footprint" ""
			(at 101.6 213.36 0)
			(effects
				(font
					(size 1.27 1.27)
					(thickness 0.15)
				)
				(justify left bottom)
				(hide yes)
			)
		)
		(property "Datasheet" ""
			(at 101.6 218.44 0)
			(effects
				(font
					(size 1.27 1.27)
					(thickness 0.15)
				)
				(justify left bottom)
				(hide yes)
			)
		)
		(property "Description" ""
			(at 92.71 205.74 0)
			(effects
				(font
					(size 1.27 1.27)
				)
				(hide yes)
			)
		)
		(property "Author" "Antmicro"
			(at 101.6 213.36 0)
			(effects
				(font
					(size 1.27 1.27)
					(thickness 0.15)
				)
				(justify left bottom)
				(hide yes)
			)
		)
		(property "License" "Apache-2.0"
			(at 101.6 215.9 0)
			(effects
				(font
					(size 1.27 1.27)
					(thickness 0.15)
				)
				(justify left bottom)
				(hide yes)
			)
		)
		(pin "1"
		)
		(instances
			(project "sdi-mipi-video-converter"
				(path ""
					(reference "#PWR0112")
					(unit 1)
				)
			)
		)
	)
	(symbol
		(lib_id "antmicropower:GND")
		(at 73.66 214.63 0)
		(unit 1)
		(exclude_from_sim no)
		(in_bom yes)
		(on_board yes)
		(dnp no)
		(fields_autoplaced yes)
		(property "Reference" "#PWR0109"
			(at 82.55 217.17 0)
			(effects
				(font
					(size 1.27 1.27)
					(thickness 0.15)
				)
				(justify left bottom)
				(hide yes)
			)
		)
		(property "Value" "GND"
			(at 73.66 219.71 0)
			(effects
				(font
					(size 1.27 1.27)
					(thickness 0.15)
				)
			)
		)
		(property "Footprint" ""
			(at 82.55 222.25 0)
			(effects
				(font
					(size 1.27 1.27)
					(thickness 0.15)
				)
				(justify left bottom)
				(hide yes)
			)
		)
		(property "Datasheet" ""
			(at 82.55 227.33 0)
			(effects
				(font
					(size 1.27 1.27)
					(thickness 0.15)
				)
				(justify left bottom)
				(hide yes)
			)
		)
		(property "Description" ""
			(at 73.66 214.63 0)
			(effects
				(font
					(size 1.27 1.27)
				)
				(hide yes)
			)
		)
		(property "Author" "Antmicro"
			(at 82.55 222.25 0)
			(effects
				(font
					(size 1.27 1.27)
					(thickness 0.15)
				)
				(justify left bottom)
				(hide yes)
			)
		)
		(property "License" "Apache-2.0"
			(at 82.55 224.79 0)
			(effects
				(font
					(size 1.27 1.27)
					(thickness 0.15)
				)
				(justify left bottom)
				(hide yes)
			)
		)
		(pin "1"
		)
		(instances
			(project "sdi-mipi-video-converter"
				(path ""
					(reference "#PWR0109")
					(unit 1)
				)
			)
		)
	)
	(symbol
		(lib_id "antmicroResistors0402:R_1k_0402")
		(at 184.15 165.1 90)
		(unit 1)
		(exclude_from_sim no)
		(in_bom yes)
		(on_board yes)
		(dnp no)
		(fields_autoplaced yes)
		(property "Reference" "R137"
			(at 181.61 161.2899 90)
			(effects
				(font
					(size 1.27 1.27)
					(thickness 0.15)
				)
				(justify left)
			)
		)
		(property "Value" "R_1k_0402"
			(at 196.85 144.78 0)
			(effects
				(font
					(size 1.27 1.27)
					(thickness 0.15)
				)
				(justify left bottom)
				(hide yes)
			)
		)
		(property "Footprint" "antmicro-footprints:R_0402_1005Metric"
			(at 199.39 144.78 0)
			(effects
				(font
					(size 1.27 1.27)
					(thickness 0.15)
				)
				(justify left bottom)
				(hide yes)
			)
		)
		(property "Datasheet" "https://www.bourns.com/docs/product-datasheets/cr.pdf"
			(at 201.93 144.78 0)
			(effects
				(font
					(size 1.27 1.27)
					(thickness 0.15)
				)
				(justify left bottom)
				(hide yes)
			)
		)
		(property "Description" "SMD Chip Resistor, 1 kohm, ± 1%, 63 mW, 0402 [1005 Metric], Thick Film, General Purpose"
			(at 184.15 165.1 0)
			(effects
				(font
					(size 1.27 1.27)
				)
				(hide yes)
			)
		)
		(property "Manufacturer" "Bourns"
			(at 207.01 144.78 0)
			(effects
				(font
					(size 1.27 1.27)
					(thickness 0.15)
				)
				(justify left bottom)
				(hide yes)
			)
		)
		(property "MPN" "CR0402-FX-1001GLF"
			(at 204.47 144.78 0)
			(effects
				(font
					(size 1.27 1.27)
					(thickness 0.15)
				)
				(justify left bottom)
				(hide yes)
			)
		)
		(property "Val" "1k"
			(at 181.61 163.8299 90)
			(effects
				(font
					(size 1.27 1.27)
					(thickness 0.15)
				)
				(justify left)
			)
		)
		(property "License" "Apache-2.0"
			(at 209.55 144.78 0)
			(effects
				(font
					(size 1.27 1.27)
					(thickness 0.15)
				)
				(justify left bottom)
				(hide yes)
			)
		)
		(property "Author" "Antmicro"
			(at 212.09 144.78 0)
			(effects
				(font
					(size 1.27 1.27)
					(thickness 0.15)
				)
				(justify left bottom)
				(hide yes)
			)
		)
		(property "Tolerance" "1%"
			(at 194.31 144.78 0)
			(effects
				(font
					(size 1.27 1.27)
				)
				(justify left bottom)
				(hide yes)
			)
		)
		(pin "1"
		)
		(pin "2"
		)
		(instances
			(project "sdi-mipi-video-converter"
				(path ""
					(reference "R137")
					(unit 1)
				)
			)
		)
	)
	(symbol
		(lib_id "antmicroTestPoints:TP_0.75mm_SMD")
		(at 168.91 180.34 0)
		(unit 1)
		(exclude_from_sim no)
		(in_bom yes)
		(on_board yes)
		(dnp no)
		(fields_autoplaced yes)
		(property "Reference" "TP33"
			(at 173.99 180.3399 0)
			(effects
				(font
					(size 1.27 1.27)
					(thickness 0.15)
				)
				(justify left)
			)
		)
		(property "Value" "TP_0.75mm_SMD"
			(at 186.69 187.96 0)
			(effects
				(font
					(size 1.27 1.27)
					(thickness 0.15)
				)
				(justify left bottom)
				(hide yes)
			)
		)
		(property "Footprint" "antmicro-footprints:TP_SMD_0.75mm"
			(at 186.69 190.5 0)
			(effects
				(font
					(size 1.27 1.27)
					(thickness 0.15)
				)
				(justify left bottom)
				(hide yes)
			)
		)
		(property "Datasheet" ""
			(at 186.69 193.04 0)
			(effects
				(font
					(size 1.27 1.27)
					(thickness 0.15)
				)
				(justify left bottom)
				(hide yes)
			)
		)
		(property "Description" "SMT test point"
			(at 168.91 180.34 0)
			(effects
				(font
					(size 1.27 1.27)
				)
				(hide yes)
			)
		)
		(property "MPN" ""
			(at 186.69 195.58 0)
			(effects
				(font
					(size 1.27 1.27)
					(thickness 0.15)
				)
				(justify left bottom)
				(hide yes)
			)
		)
		(property "Manufacturer" ""
			(at 186.69 198.12 0)
			(effects
				(font
					(size 1.27 1.27)
					(thickness 0.15)
				)
				(justify left bottom)
				(hide yes)
			)
		)
		(property "Author" "Antmicro"
			(at 186.69 200.66 0)
			(effects
				(font
					(size 1.27 1.27)
					(thickness 0.15)
				)
				(justify left bottom)
				(hide yes)
			)
		)
		(property "License" "Apache-2.0"
			(at 186.69 203.2 0)
			(effects
				(font
					(size 1.27 1.27)
					(thickness 0.15)
				)
				(justify left bottom)
				(hide yes)
			)
		)
		(pin "1"
		)
		(instances
			(project "sdi-mipi-video-converter"
				(path ""
					(reference "TP33")
					(unit 1)
				)
			)
		)
	)
	(symbol
		(lib_id "antmicroCapacitors0402:C_4u7_0402")
		(at 349.25 93.98 0)
		(mirror x)
		(unit 1)
		(exclude_from_sim no)
		(in_bom yes)
		(on_board yes)
		(dnp no)
		(fields_autoplaced yes)
		(property "Reference" "C78"
			(at 351.7963 87.63 0)
			(effects
				(font
					(size 1.27 1.27)
					(thickness 0.15)
				)
			)
		)
		(property "Value" "C_4u7_0402"
			(at 369.57 83.82 0)
			(effects
				(font
					(size 1.27 1.27)
					(thickness 0.15)
				)
				(justify left bottom)
				(hide yes)
			)
		)
		(property "Footprint" "antmicro-footprints:C_0402_1005Metric"
			(at 369.57 81.28 0)
			(effects
				(font
					(size 1.27 1.27)
					(thickness 0.15)
				)
				(justify left bottom)
				(hide yes)
			)
		)
		(property "Datasheet" "https://www.murata.com/products/productdetail?partno=GRM155R61A475MEAA%23"
			(at 369.57 78.74 0)
			(effects
				(font
					(size 1.27 1.27)
					(thickness 0.15)
				)
				(justify left bottom)
				(hide yes)
			)
		)
		(property "Description" "SMD Multilayer Ceramic Capacitor, 4.7 µF, 10 V, 0402 [1005 Metric], ± 20%, X5R, GRM Series"
			(at 349.25 93.98 0)
			(effects
				(font
					(size 1.27 1.27)
				)
				(hide yes)
			)
		)
		(property "Manufacturer" "Murata"
			(at 369.57 73.66 0)
			(effects
				(font
					(size 1.27 1.27)
					(thickness 0.15)
				)
				(justify left bottom)
				(hide yes)
			)
		)
		(property "MPN" "GRM155R61A475MEAAD"
			(at 369.57 76.2 0)
			(effects
				(font
					(size 1.27 1.27)
					(thickness 0.15)
				)
				(justify left bottom)
				(hide yes)
			)
		)
		(property "Val" "4u7"
			(at 351.7963 90.17 0)
			(effects
				(font
					(size 1.27 1.27)
					(thickness 0.15)
				)
			)
		)
		(property "License" "Apache-2.0"
			(at 369.57 71.12 0)
			(effects
				(font
					(size 1.27 1.27)
					(thickness 0.15)
				)
				(justify left bottom)
				(hide yes)
			)
		)
		(property "Author" "Antmicro"
			(at 369.57 68.58 0)
			(effects
				(font
					(size 1.27 1.27)
					(thickness 0.15)
				)
				(justify left bottom)
				(hide yes)
			)
		)
		(property "Voltage" ""
			(at 369.57 66.04 0)
			(effects
				(font
					(size 1.27 1.27)
				)
				(justify left bottom)
				(hide yes)
			)
		)
		(property "Dielectric" ""
			(at 369.57 63.5 0)
			(effects
				(font
					(size 1.27 1.27)
				)
				(justify left bottom)
				(hide yes)
			)
		)
		(pin "1"
		)
		(pin "2"
		)
		(instances
			(project "sdi-mipi-video-converter"
				(path ""
					(reference "C78")
					(unit 1)
				)
			)
		)
	)
	(symbol
		(lib_id "antmicropower:+3.3V")
		(at 190.5 158.75 0)
		(unit 1)
		(exclude_from_sim no)
		(in_bom yes)
		(on_board yes)
		(dnp no)
		(fields_autoplaced yes)
		(property "Reference" "#PWR0270"
			(at 190.5 162.56 0)
			(effects
				(font
					(size 1.27 1.27)
				)
				(hide yes)
			)
		)
		(property "Value" "+3V3"
			(at 190.5 153.67 0)
			(effects
				(font
					(size 1.27 1.27)
				)
			)
		)
		(property "Footprint" ""
			(at 190.5 158.75 0)
			(effects
				(font
					(size 1.27 1.27)
				)
				(hide yes)
			)
		)
		(property "Datasheet" ""
			(at 190.5 158.75 0)
			(effects
				(font
					(size 1.27 1.27)
				)
				(hide yes)
			)
		)
		(property "Description" ""
			(at 190.5 158.75 0)
			(effects
				(font
					(size 1.27 1.27)
				)
				(hide yes)
			)
		)
		(pin "1"
		)
		(instances
			(project "sdi-mipi-video-converter"
				(path ""
					(reference "#PWR0270")
					(unit 1)
				)
			)
		)
	)
	(symbol
		(lib_id "antmicropower:GND")
		(at 259.08 193.04 0)
		(unit 1)
		(exclude_from_sim no)
		(in_bom yes)
		(on_board yes)
		(dnp no)
		(fields_autoplaced yes)
		(property "Reference" "#PWR0130"
			(at 267.97 195.58 0)
			(effects
				(font
					(size 1.27 1.27)
					(thickness 0.15)
				)
				(justify left bottom)
				(hide yes)
			)
		)
		(property "Value" "GND"
			(at 259.08 198.12 0)
			(effects
				(font
					(size 1.27 1.27)
					(thickness 0.15)
				)
			)
		)
		(property "Footprint" ""
			(at 267.97 200.66 0)
			(effects
				(font
					(size 1.27 1.27)
					(thickness 0.15)
				)
				(justify left bottom)
				(hide yes)
			)
		)
		(property "Datasheet" ""
			(at 267.97 205.74 0)
			(effects
				(font
					(size 1.27 1.27)
					(thickness 0.15)
				)
				(justify left bottom)
				(hide yes)
			)
		)
		(property "Description" ""
			(at 259.08 193.04 0)
			(effects
				(font
					(size 1.27 1.27)
				)
				(hide yes)
			)
		)
		(property "Author" "Antmicro"
			(at 267.97 200.66 0)
			(effects
				(font
					(size 1.27 1.27)
					(thickness 0.15)
				)
				(justify left bottom)
				(hide yes)
			)
		)
		(property "License" "Apache-2.0"
			(at 267.97 203.2 0)
			(effects
				(font
					(size 1.27 1.27)
					(thickness 0.15)
				)
				(justify left bottom)
				(hide yes)
			)
		)
		(pin "1"
		)
		(instances
			(project "sdi-mipi-video-converter"
				(path ""
					(reference "#PWR0130")
					(unit 1)
				)
			)
		)
	)
	(symbol
		(lib_id "antmicropower:GND")
		(at 259.08 238.76 0)
		(unit 1)
		(exclude_from_sim no)
		(in_bom yes)
		(on_board yes)
		(dnp no)
		(fields_autoplaced yes)
		(property "Reference" "#PWR0132"
			(at 267.97 241.3 0)
			(effects
				(font
					(size 1.27 1.27)
					(thickness 0.15)
				)
				(justify left bottom)
				(hide yes)
			)
		)
		(property "Value" "GND"
			(at 259.08 243.84 0)
			(effects
				(font
					(size 1.27 1.27)
					(thickness 0.15)
				)
			)
		)
		(property "Footprint" ""
			(at 267.97 246.38 0)
			(effects
				(font
					(size 1.27 1.27)
					(thickness 0.15)
				)
				(justify left bottom)
				(hide yes)
			)
		)
		(property "Datasheet" ""
			(at 267.97 251.46 0)
			(effects
				(font
					(size 1.27 1.27)
					(thickness 0.15)
				)
				(justify left bottom)
				(hide yes)
			)
		)
		(property "Description" ""
			(at 259.08 238.76 0)
			(effects
				(font
					(size 1.27 1.27)
				)
				(hide yes)
			)
		)
		(property "Author" "Antmicro"
			(at 267.97 246.38 0)
			(effects
				(font
					(size 1.27 1.27)
					(thickness 0.15)
				)
				(justify left bottom)
				(hide yes)
			)
		)
		(property "License" "Apache-2.0"
			(at 267.97 248.92 0)
			(effects
				(font
					(size 1.27 1.27)
					(thickness 0.15)
				)
				(justify left bottom)
				(hide yes)
			)
		)
		(pin "1"
		)
		(instances
			(project "sdi-mipi-video-converter"
				(path ""
					(reference "#PWR0132")
					(unit 1)
				)
			)
		)
	)
	(symbol
		(lib_id "antmicroResistors0402:R_1k_0402")
		(at 182.88 185.42 90)
		(unit 1)
		(exclude_from_sim no)
		(in_bom no)
		(on_board yes)
		(dnp yes)
		(property "Reference" "R138"
			(at 184.15 181.61 90)
			(effects
				(font
					(size 1.27 1.27)
					(thickness 0.15)
				)
				(justify right)
			)
		)
		(property "Value" "R_1k_0402"
			(at 195.58 165.1 0)
			(effects
				(font
					(size 1.27 1.27)
					(thickness 0.15)
				)
				(justify left bottom)
				(hide yes)
			)
		)
		(property "Footprint" "antmicro-footprints:R_0402_1005Metric"
			(at 198.12 165.1 0)
			(effects
				(font
					(size 1.27 1.27)
					(thickness 0.15)
				)
				(justify left bottom)
				(hide yes)
			)
		)
		(property "Datasheet" "https://www.bourns.com/docs/product-datasheets/cr.pdf"
			(at 200.66 165.1 0)
			(effects
				(font
					(size 1.27 1.27)
					(thickness 0.15)
				)
				(justify left bottom)
				(hide yes)
			)
		)
		(property "Description" "SMD Chip Resistor, 1 kohm, ± 1%, 63 mW, 0402 [1005 Metric], Thick Film, General Purpose"
			(at 182.88 185.42 0)
			(effects
				(font
					(size 1.27 1.27)
				)
				(hide yes)
			)
		)
		(property "Manufacturer" "Bourns"
			(at 205.74 165.1 0)
			(effects
				(font
					(size 1.27 1.27)
					(thickness 0.15)
				)
				(justify left bottom)
				(hide yes)
			)
		)
		(property "MPN" "CR0402-FX-1001GLF"
			(at 203.2 165.1 0)
			(effects
				(font
					(size 1.27 1.27)
					(thickness 0.15)
				)
				(justify left bottom)
				(hide yes)
			)
		)
		(property "Val" "1k"
			(at 184.15 184.15 90)
			(effects
				(font
					(size 1.27 1.27)
					(thickness 0.15)
				)
				(justify right)
			)
		)
		(property "License" "Apache-2.0"
			(at 208.28 165.1 0)
			(effects
				(font
					(size 1.27 1.27)
					(thickness 0.15)
				)
				(justify left bottom)
				(hide yes)
			)
		)
		(property "Author" "Antmicro"
			(at 210.82 165.1 0)
			(effects
				(font
					(size 1.27 1.27)
					(thickness 0.15)
				)
				(justify left bottom)
				(hide yes)
			)
		)
		(property "Tolerance" "1%"
			(at 193.04 165.1 0)
			(effects
				(font
					(size 1.27 1.27)
				)
				(justify left bottom)
				(hide yes)
			)
		)
		(pin "1"
		)
		(pin "2"
		)
		(instances
			(project "sdi-mipi-video-converter"
				(path ""
					(reference "R138")
					(unit 1)
				)
			)
		)
	)
	(symbol
		(lib_id "antmicroTestPoints:TP_0.75mm_SMD")
		(at 132.08 234.95 0)
		(unit 1)
		(exclude_from_sim no)
		(in_bom yes)
		(on_board yes)
		(dnp no)
		(fields_autoplaced yes)
		(property "Reference" "TP26"
			(at 137.16 234.9499 0)
			(effects
				(font
					(size 1.27 1.27)
					(thickness 0.15)
				)
				(justify left)
			)
		)
		(property "Value" "TP_0.75mm_SMD"
			(at 149.86 242.57 0)
			(effects
				(font
					(size 1.27 1.27)
					(thickness 0.15)
				)
				(justify left bottom)
				(hide yes)
			)
		)
		(property "Footprint" "antmicro-footprints:TP_SMD_0.75mm"
			(at 149.86 245.11 0)
			(effects
				(font
					(size 1.27 1.27)
					(thickness 0.15)
				)
				(justify left bottom)
				(hide yes)
			)
		)
		(property "Datasheet" ""
			(at 149.86 247.65 0)
			(effects
				(font
					(size 1.27 1.27)
					(thickness 0.15)
				)
				(justify left bottom)
				(hide yes)
			)
		)
		(property "Description" "SMT test point"
			(at 132.08 234.95 0)
			(effects
				(font
					(size 1.27 1.27)
				)
				(hide yes)
			)
		)
		(property "MPN" ""
			(at 149.86 250.19 0)
			(effects
				(font
					(size 1.27 1.27)
					(thickness 0.15)
				)
				(justify left bottom)
				(hide yes)
			)
		)
		(property "Manufacturer" ""
			(at 149.86 252.73 0)
			(effects
				(font
					(size 1.27 1.27)
					(thickness 0.15)
				)
				(justify left bottom)
				(hide yes)
			)
		)
		(property "Author" "Antmicro"
			(at 149.86 255.27 0)
			(effects
				(font
					(size 1.27 1.27)
					(thickness 0.15)
				)
				(justify left bottom)
				(hide yes)
			)
		)
		(property "License" "Apache-2.0"
			(at 149.86 257.81 0)
			(effects
				(font
					(size 1.27 1.27)
					(thickness 0.15)
				)
				(justify left bottom)
				(hide yes)
			)
		)
		(pin "1"
		)
		(instances
			(project "sdi-mipi-video-converter"
				(path ""
					(reference "TP26")
					(unit 1)
				)
			)
		)
	)
	(symbol
		(lib_id "antmicropower:GND")
		(at 92.71 170.18 0)
		(unit 1)
		(exclude_from_sim no)
		(in_bom yes)
		(on_board yes)
		(dnp no)
		(property "Reference" "#PWR0110"
			(at 101.6 172.72 0)
			(effects
				(font
					(size 1.27 1.27)
					(thickness 0.15)
				)
				(justify left bottom)
				(hide yes)
			)
		)
		(property "Value" "GND"
			(at 92.71 173.99 0)
			(effects
				(font
					(size 1.27 1.27)
					(thickness 0.15)
				)
			)
		)
		(property "Footprint" ""
			(at 101.6 177.8 0)
			(effects
				(font
					(size 1.27 1.27)
					(thickness 0.15)
				)
				(justify left bottom)
				(hide yes)
			)
		)
		(property "Datasheet" ""
			(at 101.6 182.88 0)
			(effects
				(font
					(size 1.27 1.27)
					(thickness 0.15)
				)
				(justify left bottom)
				(hide yes)
			)
		)
		(property "Description" ""
			(at 92.71 170.18 0)
			(effects
				(font
					(size 1.27 1.27)
				)
				(hide yes)
			)
		)
		(property "Author" "Antmicro"
			(at 101.6 177.8 0)
			(effects
				(font
					(size 1.27 1.27)
					(thickness 0.15)
				)
				(justify left bottom)
				(hide yes)
			)
		)
		(property "License" "Apache-2.0"
			(at 101.6 180.34 0)
			(effects
				(font
					(size 1.27 1.27)
					(thickness 0.15)
				)
				(justify left bottom)
				(hide yes)
			)
		)
		(pin "1"
		)
		(instances
			(project "sdi-mipi-video-converter"
				(path ""
					(reference "#PWR0110")
					(unit 1)
				)
			)
		)
	)
	(symbol
		(lib_id "antmicroCapacitors0402:C_100n_0402")
		(at 247.65 256.54 90)
		(unit 1)
		(exclude_from_sim no)
		(in_bom yes)
		(on_board yes)
		(dnp no)
		(fields_autoplaced yes)
		(property "Reference" "C64"
			(at 250.19 252.7235 90)
			(effects
				(font
					(size 1.27 1.27)
					(thickness 0.15)
				)
				(justify right)
			)
		)
		(property "Value" "C_100n_0402"
			(at 257.81 236.22 0)
			(effects
				(font
					(size 1.27 1.27)
					(thickness 0.15)
				)
				(justify left bottom)
				(hide yes)
			)
		)
		(property "Footprint" "antmicro-footprints:C_0402_1005Metric"
			(at 260.35 236.22 0)
			(effects
				(font
					(size 1.27 1.27)
					(thickness 0.15)
				)
				(justify left bottom)
				(hide yes)
			)
		)
		(property "Datasheet" "https://www.murata.com/products/productdetail?partno=GRM155R61H104KE14%23"
			(at 262.89 236.22 0)
			(effects
				(font
					(size 1.27 1.27)
					(thickness 0.15)
				)
				(justify left bottom)
				(hide yes)
			)
		)
		(property "Description" "SMD Multilayer Ceramic Capacitor, 0.1 µF, 50 V, 0402 [1005 Metric], ± 10%, X5R, GRM Series"
			(at 247.65 256.54 0)
			(effects
				(font
					(size 1.27 1.27)
				)
				(hide yes)
			)
		)
		(property "Manufacturer" "Murata"
			(at 267.97 236.22 0)
			(effects
				(font
					(size 1.27 1.27)
					(thickness 0.15)
				)
				(justify left bottom)
				(hide yes)
			)
		)
		(property "MPN" "GRM155R61H104KE14D"
			(at 265.43 236.22 0)
			(effects
				(font
					(size 1.27 1.27)
					(thickness 0.15)
				)
				(justify left bottom)
				(hide yes)
			)
		)
		(property "Val" "100n"
			(at 250.19 255.2635 90)
			(effects
				(font
					(size 1.27 1.27)
					(thickness 0.15)
				)
				(justify right)
			)
		)
		(property "License" "Apache-2.0"
			(at 270.51 236.22 0)
			(effects
				(font
					(size 1.27 1.27)
					(thickness 0.15)
				)
				(justify left bottom)
				(hide yes)
			)
		)
		(property "Author" "Antmicro"
			(at 273.05 236.22 0)
			(effects
				(font
					(size 1.27 1.27)
					(thickness 0.15)
				)
				(justify left bottom)
				(hide yes)
			)
		)
		(property "Voltage" "50V"
			(at 275.59 236.22 0)
			(effects
				(font
					(size 1.27 1.27)
				)
				(justify left bottom)
				(hide yes)
			)
		)
		(property "Dielectric" "X5R"
			(at 278.13 236.22 0)
			(effects
				(font
					(size 1.27 1.27)
				)
				(justify left bottom)
				(hide yes)
			)
		)
		(pin "1"
		)
		(pin "2"
		)
		(instances
			(project "sdi-mipi-video-converter"
				(path ""
					(reference "C64")
					(unit 1)
				)
			)
		)
	)
	(symbol
		(lib_id "antmicroTestPoints:TP_0.75mm_SMD")
		(at 168.91 205.74 0)
		(unit 1)
		(exclude_from_sim no)
		(in_bom yes)
		(on_board yes)
		(dnp no)
		(fields_autoplaced yes)
		(property "Reference" "TP43"
			(at 173.99 205.7399 0)
			(effects
				(font
					(size 1.27 1.27)
					(thickness 0.15)
				)
				(justify left)
			)
		)
		(property "Value" "TP_0.75mm_SMD"
			(at 186.69 213.36 0)
			(effects
				(font
					(size 1.27 1.27)
					(thickness 0.15)
				)
				(justify left bottom)
				(hide yes)
			)
		)
		(property "Footprint" "antmicro-footprints:TP_SMD_0.75mm"
			(at 186.69 215.9 0)
			(effects
				(font
					(size 1.27 1.27)
					(thickness 0.15)
				)
				(justify left bottom)
				(hide yes)
			)
		)
		(property "Datasheet" ""
			(at 186.69 218.44 0)
			(effects
				(font
					(size 1.27 1.27)
					(thickness 0.15)
				)
				(justify left bottom)
				(hide yes)
			)
		)
		(property "Description" "SMT test point"
			(at 168.91 205.74 0)
			(effects
				(font
					(size 1.27 1.27)
				)
				(hide yes)
			)
		)
		(property "MPN" ""
			(at 186.69 220.98 0)
			(effects
				(font
					(size 1.27 1.27)
					(thickness 0.15)
				)
				(justify left bottom)
				(hide yes)
			)
		)
		(property "Manufacturer" ""
			(at 186.69 223.52 0)
			(effects
				(font
					(size 1.27 1.27)
					(thickness 0.15)
				)
				(justify left bottom)
				(hide yes)
			)
		)
		(property "Author" "Antmicro"
			(at 186.69 226.06 0)
			(effects
				(font
					(size 1.27 1.27)
					(thickness 0.15)
				)
				(justify left bottom)
				(hide yes)
			)
		)
		(property "License" "Apache-2.0"
			(at 186.69 228.6 0)
			(effects
				(font
					(size 1.27 1.27)
					(thickness 0.15)
				)
				(justify left bottom)
				(hide yes)
			)
		)
		(pin "1"
		)
		(instances
			(project "sdi-mipi-video-converter"
				(path ""
					(reference "TP43")
					(unit 1)
				)
			)
		)
	)
	(symbol
		(lib_id "antmicroTestPoints:TP_0.75mm_SMD")
		(at 168.91 200.66 0)
		(unit 1)
		(exclude_from_sim no)
		(in_bom yes)
		(on_board yes)
		(dnp no)
		(fields_autoplaced yes)
		(property "Reference" "TP41"
			(at 173.99 200.6599 0)
			(effects
				(font
					(size 1.27 1.27)
					(thickness 0.15)
				)
				(justify left)
			)
		)
		(property "Value" "TP_0.75mm_SMD"
			(at 186.69 208.28 0)
			(effects
				(font
					(size 1.27 1.27)
					(thickness 0.15)
				)
				(justify left bottom)
				(hide yes)
			)
		)
		(property "Footprint" "antmicro-footprints:TP_SMD_0.75mm"
			(at 186.69 210.82 0)
			(effects
				(font
					(size 1.27 1.27)
					(thickness 0.15)
				)
				(justify left bottom)
				(hide yes)
			)
		)
		(property "Datasheet" ""
			(at 186.69 213.36 0)
			(effects
				(font
					(size 1.27 1.27)
					(thickness 0.15)
				)
				(justify left bottom)
				(hide yes)
			)
		)
		(property "Description" "SMT test point"
			(at 168.91 200.66 0)
			(effects
				(font
					(size 1.27 1.27)
				)
				(hide yes)
			)
		)
		(property "MPN" ""
			(at 186.69 215.9 0)
			(effects
				(font
					(size 1.27 1.27)
					(thickness 0.15)
				)
				(justify left bottom)
				(hide yes)
			)
		)
		(property "Manufacturer" ""
			(at 186.69 218.44 0)
			(effects
				(font
					(size 1.27 1.27)
					(thickness 0.15)
				)
				(justify left bottom)
				(hide yes)
			)
		)
		(property "Author" "Antmicro"
			(at 186.69 220.98 0)
			(effects
				(font
					(size 1.27 1.27)
					(thickness 0.15)
				)
				(justify left bottom)
				(hide yes)
			)
		)
		(property "License" "Apache-2.0"
			(at 186.69 223.52 0)
			(effects
				(font
					(size 1.27 1.27)
					(thickness 0.15)
				)
				(justify left bottom)
				(hide yes)
			)
		)
		(pin "1"
		)
		(instances
			(project "sdi-mipi-video-converter"
				(path ""
					(reference "TP41")
					(unit 1)
				)
			)
		)
	)
	(symbol
		(lib_id "antmicroCapacitors0402:C_1u_0402")
		(at 102.87 173.99 270)
		(unit 1)
		(exclude_from_sim no)
		(in_bom yes)
		(on_board yes)
		(dnp no)
		(property "Reference" "C57"
			(at 103.505 174.625 90)
			(effects
				(font
					(size 1.27 1.27)
					(thickness 0.15)
				)
				(justify left)
			)
		)
		(property "Value" "C_1u_0402"
			(at 92.71 194.31 0)
			(effects
				(font
					(size 1.27 1.27)
					(thickness 0.15)
				)
				(justify left bottom)
				(hide yes)
			)
		)
		(property "Footprint" "antmicro-footprints:C_0402_1005Metric"
			(at 90.17 194.31 0)
			(effects
				(font
					(size 1.27 1.27)
					(thickness 0.15)
				)
				(justify left bottom)
				(hide yes)
			)
		)
		(property "Datasheet" "https://product.tdk.com/en/search/capacitor/ceramic/mlcc/info?part_no=C1005X6S1A105K050BC"
			(at 87.63 194.31 0)
			(effects
				(font
					(size 1.27 1.27)
					(thickness 0.15)
				)
				(justify left bottom)
				(hide yes)
			)
		)
		(property "Description" "SMD Multilayer Ceramic Capacitor, 1 µF, 10 V, 0402 [1005 Metric], ± 10%, X6S, C"
			(at 102.87 173.99 0)
			(effects
				(font
					(size 1.27 1.27)
				)
				(hide yes)
			)
		)
		(property "Manufacturer" "TDK"
			(at 82.55 194.31 0)
			(effects
				(font
					(size 1.27 1.27)
					(thickness 0.15)
				)
				(justify left bottom)
				(hide yes)
			)
		)
		(property "MPN" "C1005X6S1A105K050BC"
			(at 85.09 194.31 0)
			(effects
				(font
					(size 1.27 1.27)
					(thickness 0.15)
				)
				(justify left bottom)
				(hide yes)
			)
		)
		(property "Val" "1u"
			(at 103.505 178.435 90)
			(effects
				(font
					(size 1.27 1.27)
					(thickness 0.15)
				)
				(justify left)
			)
		)
		(property "License" "Apache-2.0"
			(at 80.01 194.31 0)
			(effects
				(font
					(size 1.27 1.27)
					(thickness 0.15)
				)
				(justify left bottom)
				(hide yes)
			)
		)
		(property "Author" "Antmicro"
			(at 77.47 194.31 0)
			(effects
				(font
					(size 1.27 1.27)
					(thickness 0.15)
				)
				(justify left bottom)
				(hide yes)
			)
		)
		(property "Voltage" ""
			(at 74.93 194.31 0)
			(effects
				(font
					(size 1.27 1.27)
				)
				(justify left bottom)
				(hide yes)
			)
		)
		(property "Dielectric" ""
			(at 72.39 194.31 0)
			(effects
				(font
					(size 1.27 1.27)
				)
				(justify left bottom)
				(hide yes)
			)
		)
		(pin "1"
		)
		(pin "2"
		)
		(instances
			(project "sdi-mipi-video-converter"
				(path ""
					(reference "C57")
					(unit 1)
				)
			)
		)
	)
	(symbol
		(lib_id "antmicroCoaxialConnectorsRF:Conn_BNC_031-70526-21")
		(at 38.1 199.39 0)
		(mirror y)
		(unit 1)
		(exclude_from_sim no)
		(in_bom yes)
		(on_board yes)
		(dnp no)
		(fields_autoplaced yes)
		(property "Reference" "J2"
			(at 33.4009 191.77 0)
			(effects
				(font
					(size 1.27 1.27)
					(thickness 0.15)
				)
			)
		)
		(property "Value" "Conn_BNC_031-70526-21"
			(at 33.4009 194.31 0)
			(effects
				(font
					(size 1.27 1.27)
					(thickness 0.15)
				)
			)
		)
		(property "Footprint" "antmicro-footprints:Conn_BNC_031-70526-21"
			(at 17.78 209.55 0)
			(effects
				(font
					(size 1.27 1.27)
					(thickness 0.15)
				)
				(justify left bottom)
				(hide yes)
			)
		)
		(property "Datasheet" "https://www.farnell.com/cad/2305565.pdf?_ga=2.190633003.1014497200.1574067480-156563690.1566371002&_gac=1.57062104.1572875319.Cj0KCQiAtf_tBRDtARIsAIbAKe0A1M5y_jdFCiNLNrHM5L2GjmDvn_4qnRvhHAD9jBdL9AmoMNThLCoaAjhJEALw_wcB"
			(at 17.78 212.09 0)
			(effects
				(font
					(size 1.27 1.27)
					(thickness 0.15)
				)
				(justify left bottom)
				(hide yes)
			)
		)
		(property "Description" "RF / Coaxial Connector, BNC Coaxial, Straight Bulkhead Jack, Board Edge / End Launch, 75 ohm"
			(at 38.1 199.39 0)
			(effects
				(font
					(size 1.27 1.27)
				)
				(hide yes)
			)
		)
		(property "MPN" "031-70526-21"
			(at 17.78 214.63 0)
			(effects
				(font
					(size 1.27 1.27)
					(thickness 0.15)
				)
				(justify left bottom)
				(hide yes)
			)
		)
		(property "Manufacturer" "Amphenol"
			(at 17.78 217.17 0)
			(effects
				(font
					(size 1.27 1.27)
					(thickness 0.15)
				)
				(justify left bottom)
				(hide yes)
			)
		)
		(property "Author" "Antmicro"
			(at 17.78 219.71 0)
			(effects
				(font
					(size 1.27 1.27)
					(thickness 0.15)
				)
				(justify left bottom)
				(hide yes)
			)
		)
		(property "License" "Apache-2.0"
			(at 17.78 222.25 0)
			(effects
				(font
					(size 1.27 1.27)
					(thickness 0.15)
				)
				(justify left bottom)
				(hide yes)
			)
		)
		(pin "1"
		)
		(pin "2"
		)
		(instances
			(project "sdi-mipi-video-converter"
				(path ""
					(reference "J2")
					(unit 1)
				)
			)
		)
	)
	(symbol
		(lib_id "antmicroCapacitors0402:C_100n_0402")
		(at 236.22 256.54 90)
		(unit 1)
		(exclude_from_sim no)
		(in_bom yes)
		(on_board yes)
		(dnp no)
		(fields_autoplaced yes)
		(property "Reference" "C60"
			(at 238.76 252.7235 90)
			(effects
				(font
					(size 1.27 1.27)
					(thickness 0.15)
				)
				(justify right)
			)
		)
		(property "Value" "C_100n_0402"
			(at 246.38 236.22 0)
			(effects
				(font
					(size 1.27 1.27)
					(thickness 0.15)
				)
				(justify left bottom)
				(hide yes)
			)
		)
		(property "Footprint" "antmicro-footprints:C_0402_1005Metric"
			(at 248.92 236.22 0)
			(effects
				(font
					(size 1.27 1.27)
					(thickness 0.15)
				)
				(justify left bottom)
				(hide yes)
			)
		)
		(property "Datasheet" "https://www.murata.com/products/productdetail?partno=GRM155R61H104KE14%23"
			(at 251.46 236.22 0)
			(effects
				(font
					(size 1.27 1.27)
					(thickness 0.15)
				)
				(justify left bottom)
				(hide yes)
			)
		)
		(property "Description" "SMD Multilayer Ceramic Capacitor, 0.1 µF, 50 V, 0402 [1005 Metric], ± 10%, X5R, GRM Series"
			(at 236.22 256.54 0)
			(effects
				(font
					(size 1.27 1.27)
				)
				(hide yes)
			)
		)
		(property "Manufacturer" "Murata"
			(at 256.54 236.22 0)
			(effects
				(font
					(size 1.27 1.27)
					(thickness 0.15)
				)
				(justify left bottom)
				(hide yes)
			)
		)
		(property "MPN" "GRM155R61H104KE14D"
			(at 254 236.22 0)
			(effects
				(font
					(size 1.27 1.27)
					(thickness 0.15)
				)
				(justify left bottom)
				(hide yes)
			)
		)
		(property "Val" "100n"
			(at 238.76 255.2635 90)
			(effects
				(font
					(size 1.27 1.27)
					(thickness 0.15)
				)
				(justify right)
			)
		)
		(property "License" "Apache-2.0"
			(at 259.08 236.22 0)
			(effects
				(font
					(size 1.27 1.27)
					(thickness 0.15)
				)
				(justify left bottom)
				(hide yes)
			)
		)
		(property "Author" "Antmicro"
			(at 261.62 236.22 0)
			(effects
				(font
					(size 1.27 1.27)
					(thickness 0.15)
				)
				(justify left bottom)
				(hide yes)
			)
		)
		(property "Voltage" "50V"
			(at 264.16 236.22 0)
			(effects
				(font
					(size 1.27 1.27)
				)
				(justify left bottom)
				(hide yes)
			)
		)
		(property "Dielectric" "X5R"
			(at 266.7 236.22 0)
			(effects
				(font
					(size 1.27 1.27)
				)
				(justify left bottom)
				(hide yes)
			)
		)
		(pin "1"
		)
		(pin "2"
		)
		(instances
			(project "sdi-mipi-video-converter"
				(path ""
					(reference "C60")
					(unit 1)
				)
			)
		)
	)
	(symbol
		(lib_id "antmicropower:+3.3V")
		(at 184.15 158.75 0)
		(unit 1)
		(exclude_from_sim no)
		(in_bom yes)
		(on_board yes)
		(dnp no)
		(fields_autoplaced yes)
		(property "Reference" "#PWR0271"
			(at 184.15 162.56 0)
			(effects
				(font
					(size 1.27 1.27)
				)
				(hide yes)
			)
		)
		(property "Value" "+3V3"
			(at 184.15 153.67 0)
			(effects
				(font
					(size 1.27 1.27)
				)
			)
		)
		(property "Footprint" ""
			(at 184.15 158.75 0)
			(effects
				(font
					(size 1.27 1.27)
				)
				(hide yes)
			)
		)
		(property "Datasheet" ""
			(at 184.15 158.75 0)
			(effects
				(font
					(size 1.27 1.27)
				)
				(hide yes)
			)
		)
		(property "Description" ""
			(at 184.15 158.75 0)
			(effects
				(font
					(size 1.27 1.27)
				)
				(hide yes)
			)
		)
		(pin "1"
		)
		(instances
			(project "sdi-mipi-video-converter"
				(path ""
					(reference "#PWR0271")
					(unit 1)
				)
			)
		)
	)
	(symbol
		(lib_id "antmicroResistors0402:R_75R_0402")
		(at 304.8 78.74 0)
		(unit 1)
		(exclude_from_sim no)
		(in_bom yes)
		(on_board yes)
		(dnp no)
		(property "Reference" "R60"
			(at 311.785 77.47 0)
			(effects
				(font
					(size 1.27 1.27)
					(thickness 0.15)
				)
			)
		)
		(property "Value" "R_75R_0402"
			(at 325.12 91.44 0)
			(effects
				(font
					(size 1.27 1.27)
					(thickness 0.15)
				)
				(justify left bottom)
				(hide yes)
			)
		)
		(property "Footprint" "antmicro-footprints:R_0402_1005Metric"
			(at 325.12 93.98 0)
			(effects
				(font
					(size 1.27 1.27)
					(thickness 0.15)
				)
				(justify left bottom)
				(hide yes)
			)
		)
		(property "Datasheet" "https://www.bourns.com/docs/product-datasheets/cr.pdf"
			(at 325.12 96.52 0)
			(effects
				(font
					(size 1.27 1.27)
					(thickness 0.15)
				)
				(justify left bottom)
				(hide yes)
			)
		)
		(property "Description" "SMD Chip Resistor, 75 ohm, ± 1%, 62.5 mW, 0402 [1005 Metric], Thick Film, General Purpose"
			(at 304.8 78.74 0)
			(effects
				(font
					(size 1.27 1.27)
				)
				(hide yes)
			)
		)
		(property "Manufacturer" "Bourns"
			(at 325.12 101.6 0)
			(effects
				(font
					(size 1.27 1.27)
					(thickness 0.15)
				)
				(justify left bottom)
				(hide yes)
			)
		)
		(property "MPN" "CR0402-FX-75R0GLF"
			(at 325.12 99.06 0)
			(effects
				(font
					(size 1.27 1.27)
					(thickness 0.15)
				)
				(justify left bottom)
				(hide yes)
			)
		)
		(property "Val" "75R"
			(at 302.895 77.47 0)
			(effects
				(font
					(size 1.27 1.27)
					(thickness 0.15)
				)
			)
		)
		(property "License" "Apache-2.0"
			(at 325.12 104.14 0)
			(effects
				(font
					(size 1.27 1.27)
					(thickness 0.15)
				)
				(justify left bottom)
				(hide yes)
			)
		)
		(property "Author" "Antmicro"
			(at 325.12 106.68 0)
			(effects
				(font
					(size 1.27 1.27)
					(thickness 0.15)
				)
				(justify left bottom)
				(hide yes)
			)
		)
		(property "Tolerance" "1%"
			(at 325.12 88.9 0)
			(effects
				(font
					(size 1.27 1.27)
				)
				(justify left bottom)
				(hide yes)
			)
		)
		(pin "1"
		)
		(pin "2"
		)
		(instances
			(project "sdi-mipi-video-converter"
				(path ""
					(reference "R60")
					(unit 1)
				)
			)
		)
	)
	(symbol
		(lib_id "antmicroTestPoints:TP_0.75mm_SMD")
		(at 168.91 170.18 0)
		(unit 1)
		(exclude_from_sim no)
		(in_bom yes)
		(on_board yes)
		(dnp no)
		(fields_autoplaced yes)
		(property "Reference" "TP29"
			(at 173.99 170.1799 0)
			(effects
				(font
					(size 1.27 1.27)
					(thickness 0.15)
				)
				(justify left)
			)
		)
		(property "Value" "TP_0.75mm_SMD"
			(at 186.69 177.8 0)
			(effects
				(font
					(size 1.27 1.27)
					(thickness 0.15)
				)
				(justify left bottom)
				(hide yes)
			)
		)
		(property "Footprint" "antmicro-footprints:TP_SMD_0.75mm"
			(at 186.69 180.34 0)
			(effects
				(font
					(size 1.27 1.27)
					(thickness 0.15)
				)
				(justify left bottom)
				(hide yes)
			)
		)
		(property "Datasheet" ""
			(at 186.69 182.88 0)
			(effects
				(font
					(size 1.27 1.27)
					(thickness 0.15)
				)
				(justify left bottom)
				(hide yes)
			)
		)
		(property "Description" "SMT test point"
			(at 168.91 170.18 0)
			(effects
				(font
					(size 1.27 1.27)
				)
				(hide yes)
			)
		)
		(property "MPN" ""
			(at 186.69 185.42 0)
			(effects
				(font
					(size 1.27 1.27)
					(thickness 0.15)
				)
				(justify left bottom)
				(hide yes)
			)
		)
		(property "Manufacturer" ""
			(at 186.69 187.96 0)
			(effects
				(font
					(size 1.27 1.27)
					(thickness 0.15)
				)
				(justify left bottom)
				(hide yes)
			)
		)
		(property "Author" "Antmicro"
			(at 186.69 190.5 0)
			(effects
				(font
					(size 1.27 1.27)
					(thickness 0.15)
				)
				(justify left bottom)
				(hide yes)
			)
		)
		(property "License" "Apache-2.0"
			(at 186.69 193.04 0)
			(effects
				(font
					(size 1.27 1.27)
					(thickness 0.15)
				)
				(justify left bottom)
				(hide yes)
			)
		)
		(pin "1"
		)
		(instances
			(project "sdi-mipi-video-converter"
				(path ""
					(reference "TP29")
					(unit 1)
				)
			)
		)
	)
	(symbol
		(lib_id "antmicropower:+3.3V")
		(at 236.22 248.92 0)
		(unit 1)
		(exclude_from_sim no)
		(in_bom yes)
		(on_board yes)
		(dnp no)
		(fields_autoplaced yes)
		(property "Reference" "#PWR0119"
			(at 236.22 252.73 0)
			(effects
				(font
					(size 1.27 1.27)
				)
				(hide yes)
			)
		)
		(property "Value" "+3V3"
			(at 236.22 243.84 0)
			(effects
				(font
					(size 1.27 1.27)
				)
			)
		)
		(property "Footprint" ""
			(at 236.22 248.92 0)
			(effects
				(font
					(size 1.27 1.27)
				)
				(hide yes)
			)
		)
		(property "Datasheet" ""
			(at 236.22 248.92 0)
			(effects
				(font
					(size 1.27 1.27)
				)
				(hide yes)
			)
		)
		(property "Description" ""
			(at 236.22 248.92 0)
			(effects
				(font
					(size 1.27 1.27)
				)
				(hide yes)
			)
		)
		(pin "1"
		)
		(instances
			(project "sdi-mipi-video-converter"
				(path ""
					(reference "#PWR0119")
					(unit 1)
				)
			)
		)
	)
	(symbol
		(lib_id "antmicroInterfaceControllers:GS2988")
		(at 264.16 77.47 0)
		(unit 1)
		(exclude_from_sim no)
		(in_bom yes)
		(on_board yes)
		(dnp no)
		(fields_autoplaced yes)
		(property "Reference" "U16"
			(at 275.59 69.85 0)
			(effects
				(font
					(size 1.27 1.27)
					(thickness 0.15)
				)
			)
		)
		(property "Value" "GS2988"
			(at 275.59 72.39 0)
			(effects
				(font
					(size 1.27 1.27)
					(thickness 0.15)
				)
			)
		)
		(property "Footprint" "antmicro-footprints:QFN-16-1EP_4x4mm_P0.65mm"
			(at 320.04 87.63 0)
			(effects
				(font
					(size 1.27 1.27)
					(thickness 0.15)
				)
				(justify left bottom)
				(hide yes)
			)
		)
		(property "Datasheet" "https://semtech.my.salesforce.com/sfc/p/#E0000000JelG/a/44000000MDIY/URmNPYk6YrvngFjCh2n.ZRVsjLb90QOH1YLezdH9vhM"
			(at 320.04 90.17 0)
			(effects
				(font
					(size 1.27 1.27)
					(thickness 0.15)
				)
				(justify left bottom)
				(hide yes)
			)
		)
		(property "Description" "SDI driver"
			(at 264.16 77.47 0)
			(effects
				(font
					(size 1.27 1.27)
				)
				(hide yes)
			)
		)
		(property "Manufacturer" "Semtech"
			(at 320.04 92.71 0)
			(effects
				(font
					(size 1.27 1.27)
					(thickness 0.15)
				)
				(justify left bottom)
				(hide yes)
			)
		)
		(property "MPN" "GS2988-INE3"
			(at 320.04 95.25 0)
			(effects
				(font
					(size 1.27 1.27)
					(thickness 0.15)
				)
				(justify left bottom)
				(hide yes)
			)
		)
		(property "Author" "Antmicro"
			(at 320.04 97.79 0)
			(effects
				(font
					(size 1.27 1.27)
					(thickness 0.15)
				)
				(justify left bottom)
				(hide yes)
			)
		)
		(property "License" "Apache-2.0"
			(at 320.04 100.33 0)
			(effects
				(font
					(size 1.27 1.27)
					(thickness 0.15)
				)
				(justify left bottom)
				(hide yes)
			)
		)
		(pin "1"
		)
		(pin "10"
		)
		(pin "11"
		)
		(pin "12"
		)
		(pin "13"
		)
		(pin "14"
		)
		(pin "15"
		)
		(pin "16"
		)
		(pin "17"
		)
		(pin "2"
		)
		(pin "3"
		)
		(pin "4"
		)
		(pin "5"
		)
		(pin "6"
		)
		(pin "7"
		)
		(pin "8"
		)
		(pin "9"
		)
		(instances
			(project "sdi-mipi-video-converter"
				(path ""
					(reference "U16")
					(unit 1)
				)
			)
		)
	)
	(symbol
		(lib_id "antmicroResistors0402:R_1k_0402")
		(at 191.77 185.42 90)
		(unit 1)
		(exclude_from_sim no)
		(in_bom no)
		(on_board yes)
		(dnp yes)
		(property "Reference" "R140"
			(at 193.04 181.61 90)
			(effects
				(font
					(size 1.27 1.27)
					(thickness 0.15)
				)
				(justify right)
			)
		)
		(property "Value" "R_1k_0402"
			(at 204.47 165.1 0)
			(effects
				(font
					(size 1.27 1.27)
					(thickness 0.15)
				)
				(justify left bottom)
				(hide yes)
			)
		)
		(property "Footprint" "antmicro-footprints:R_0402_1005Metric"
			(at 207.01 165.1 0)
			(effects
				(font
					(size 1.27 1.27)
					(thickness 0.15)
				)
				(justify left bottom)
				(hide yes)
			)
		)
		(property "Datasheet" "https://www.bourns.com/docs/product-datasheets/cr.pdf"
			(at 209.55 165.1 0)
			(effects
				(font
					(size 1.27 1.27)
					(thickness 0.15)
				)
				(justify left bottom)
				(hide yes)
			)
		)
		(property "Description" "SMD Chip Resistor, 1 kohm, ± 1%, 63 mW, 0402 [1005 Metric], Thick Film, General Purpose"
			(at 191.77 185.42 0)
			(effects
				(font
					(size 1.27 1.27)
				)
				(hide yes)
			)
		)
		(property "Manufacturer" "Bourns"
			(at 214.63 165.1 0)
			(effects
				(font
					(size 1.27 1.27)
					(thickness 0.15)
				)
				(justify left bottom)
				(hide yes)
			)
		)
		(property "MPN" "CR0402-FX-1001GLF"
			(at 212.09 165.1 0)
			(effects
				(font
					(size 1.27 1.27)
					(thickness 0.15)
				)
				(justify left bottom)
				(hide yes)
			)
		)
		(property "Val" "1k"
			(at 193.04 184.15 90)
			(effects
				(font
					(size 1.27 1.27)
					(thickness 0.15)
				)
				(justify right)
			)
		)
		(property "License" "Apache-2.0"
			(at 217.17 165.1 0)
			(effects
				(font
					(size 1.27 1.27)
					(thickness 0.15)
				)
				(justify left bottom)
				(hide yes)
			)
		)
		(property "Author" "Antmicro"
			(at 219.71 165.1 0)
			(effects
				(font
					(size 1.27 1.27)
					(thickness 0.15)
				)
				(justify left bottom)
				(hide yes)
			)
		)
		(property "Tolerance" "1%"
			(at 201.93 165.1 0)
			(effects
				(font
					(size 1.27 1.27)
				)
				(justify left bottom)
				(hide yes)
			)
		)
		(pin "1"
		)
		(pin "2"
		)
		(instances
			(project "sdi-mipi-video-converter"
				(path ""
					(reference "R140")
					(unit 1)
				)
			)
		)
	)
	(symbol
		(lib_id "antmicroCapacitors0402:C_100n_0402")
		(at 270.51 237.49 90)
		(unit 1)
		(exclude_from_sim no)
		(in_bom yes)
		(on_board yes)
		(dnp no)
		(fields_autoplaced yes)
		(property "Reference" "C73"
			(at 273.05 233.6735 90)
			(effects
				(font
					(size 1.27 1.27)
					(thickness 0.15)
				)
				(justify right)
			)
		)
		(property "Value" "C_100n_0402"
			(at 280.67 217.17 0)
			(effects
				(font
					(size 1.27 1.27)
					(thickness 0.15)
				)
				(justify left bottom)
				(hide yes)
			)
		)
		(property "Footprint" "antmicro-footprints:C_0402_1005Metric"
			(at 283.21 217.17 0)
			(effects
				(font
					(size 1.27 1.27)
					(thickness 0.15)
				)
				(justify left bottom)
				(hide yes)
			)
		)
		(property "Datasheet" "https://www.murata.com/products/productdetail?partno=GRM155R61H104KE14%23"
			(at 285.75 217.17 0)
			(effects
				(font
					(size 1.27 1.27)
					(thickness 0.15)
				)
				(justify left bottom)
				(hide yes)
			)
		)
		(property "Description" "SMD Multilayer Ceramic Capacitor, 0.1 µF, 50 V, 0402 [1005 Metric], ± 10%, X5R, GRM Series"
			(at 270.51 237.49 0)
			(effects
				(font
					(size 1.27 1.27)
				)
				(hide yes)
			)
		)
		(property "Manufacturer" "Murata"
			(at 290.83 217.17 0)
			(effects
				(font
					(size 1.27 1.27)
					(thickness 0.15)
				)
				(justify left bottom)
				(hide yes)
			)
		)
		(property "MPN" "GRM155R61H104KE14D"
			(at 288.29 217.17 0)
			(effects
				(font
					(size 1.27 1.27)
					(thickness 0.15)
				)
				(justify left bottom)
				(hide yes)
			)
		)
		(property "Val" "100n"
			(at 273.05 236.2135 90)
			(effects
				(font
					(size 1.27 1.27)
					(thickness 0.15)
				)
				(justify right)
			)
		)
		(property "License" "Apache-2.0"
			(at 293.37 217.17 0)
			(effects
				(font
					(size 1.27 1.27)
					(thickness 0.15)
				)
				(justify left bottom)
				(hide yes)
			)
		)
		(property "Author" "Antmicro"
			(at 295.91 217.17 0)
			(effects
				(font
					(size 1.27 1.27)
					(thickness 0.15)
				)
				(justify left bottom)
				(hide yes)
			)
		)
		(property "Voltage" "50V"
			(at 298.45 217.17 0)
			(effects
				(font
					(size 1.27 1.27)
				)
				(justify left bottom)
				(hide yes)
			)
		)
		(property "Dielectric" "X5R"
			(at 300.99 217.17 0)
			(effects
				(font
					(size 1.27 1.27)
				)
				(justify left bottom)
				(hide yes)
			)
		)
		(pin "1"
		)
		(pin "2"
		)
		(instances
			(project "sdi-mipi-video-converter"
				(path ""
					(reference "C73")
					(unit 1)
				)
			)
		)
	)
	(symbol
		(lib_id "antmicropower:GND")
		(at 191.77 186.69 0)
		(unit 1)
		(exclude_from_sim no)
		(in_bom yes)
		(on_board yes)
		(dnp no)
		(property "Reference" "#PWR0269"
			(at 200.66 189.23 0)
			(effects
				(font
					(size 1.27 1.27)
					(thickness 0.15)
				)
				(justify left bottom)
				(hide yes)
			)
		)
		(property "Value" "GND"
			(at 193.675 190.5 0)
			(effects
				(font
					(size 1.27 1.27)
					(thickness 0.15)
				)
				(justify right)
			)
		)
		(property "Footprint" ""
			(at 200.66 194.31 0)
			(effects
				(font
					(size 1.27 1.27)
					(thickness 0.15)
				)
				(justify left bottom)
				(hide yes)
			)
		)
		(property "Datasheet" ""
			(at 200.66 199.39 0)
			(effects
				(font
					(size 1.27 1.27)
					(thickness 0.15)
				)
				(justify left bottom)
				(hide yes)
			)
		)
		(property "Description" ""
			(at 191.77 186.69 0)
			(effects
				(font
					(size 1.27 1.27)
				)
				(hide yes)
			)
		)
		(property "Author" "Antmicro"
			(at 200.66 194.31 0)
			(effects
				(font
					(size 1.27 1.27)
					(thickness 0.15)
				)
				(justify left bottom)
				(hide yes)
			)
		)
		(property "License" "Apache-2.0"
			(at 200.66 196.85 0)
			(effects
				(font
					(size 1.27 1.27)
					(thickness 0.15)
				)
				(justify left bottom)
				(hide yes)
			)
		)
		(pin "1"
		)
		(instances
			(project "sdi-mipi-video-converter"
				(path ""
					(reference "#PWR0269")
					(unit 1)
				)
			)
		)
	)
	(symbol
		(lib_id "antmicroCapacitors0402:C_470n_0402")
		(at 99.06 193.04 180)
		(unit 1)
		(exclude_from_sim no)
		(in_bom yes)
		(on_board yes)
		(dnp no)
		(property "Reference" "C56"
			(at 96.52 190.5 0)
			(effects
				(font
					(size 1.27 1.27)
					(thickness 0.15)
				)
			)
		)
		(property "Value" "C_470n_0402"
			(at 78.74 182.88 0)
			(effects
				(font
					(size 1.27 1.27)
					(thickness 0.15)
				)
				(justify left bottom)
				(hide yes)
			)
		)
		(property "Footprint" "antmicro-footprints:C_0402_1005Metric"
			(at 78.74 180.34 0)
			(effects
				(font
					(size 1.27 1.27)
					(thickness 0.15)
				)
				(justify left bottom)
				(hide yes)
			)
		)
		(property "Datasheet" "https://product.tdk.com/en/search/capacitor/ceramic/mlcc/info?part_no=C1005X5R1E474M050BB"
			(at 78.74 177.8 0)
			(effects
				(font
					(size 1.27 1.27)
					(thickness 0.15)
				)
				(justify left bottom)
				(hide yes)
			)
		)
		(property "Description" "SMD Multilayer Ceramic Capacitor, 0.47 µF, 25 V, 0402 [1005 Metric], ± 20%, X5R, C"
			(at 99.06 193.04 0)
			(effects
				(font
					(size 1.27 1.27)
				)
				(hide yes)
			)
		)
		(property "Manufacturer" "TDK"
			(at 78.74 172.72 0)
			(effects
				(font
					(size 1.27 1.27)
					(thickness 0.15)
				)
				(justify left bottom)
				(hide yes)
			)
		)
		(property "MPN" "C1005X5R1E474M050BB"
			(at 78.74 175.26 0)
			(effects
				(font
					(size 1.27 1.27)
					(thickness 0.15)
				)
				(justify left bottom)
				(hide yes)
			)
		)
		(property "Val" "470n"
			(at 96.52 196.215 0)
			(effects
				(font
					(size 1.27 1.27)
					(thickness 0.15)
				)
			)
		)
		(property "License" "Apache-2.0"
			(at 78.74 170.18 0)
			(effects
				(font
					(size 1.27 1.27)
					(thickness 0.15)
				)
				(justify left bottom)
				(hide yes)
			)
		)
		(property "Author" "Antmicro"
			(at 78.74 167.64 0)
			(effects
				(font
					(size 1.27 1.27)
					(thickness 0.15)
				)
				(justify left bottom)
				(hide yes)
			)
		)
		(property "Voltage" ""
			(at 78.74 165.1 0)
			(effects
				(font
					(size 1.27 1.27)
				)
				(justify left bottom)
				(hide yes)
			)
		)
		(property "Dielectric" ""
			(at 78.74 162.56 0)
			(effects
				(font
					(size 1.27 1.27)
				)
				(justify left bottom)
				(hide yes)
			)
		)
		(pin "1"
		)
		(pin "2"
		)
		(instances
			(project "sdi-mipi-video-converter"
				(path ""
					(reference "C56")
					(unit 1)
				)
			)
		)
	)
	(symbol
		(lib_id "antmicroResistors0402:R_75R_0402")
		(at 62.23 213.36 270)
		(mirror x)
		(unit 1)
		(exclude_from_sim no)
		(in_bom yes)
		(on_board yes)
		(dnp no)
		(fields_autoplaced yes)
		(property "Reference" "R52"
			(at 64.77 209.5499 90)
			(effects
				(font
					(size 1.27 1.27)
					(thickness 0.15)
				)
				(justify left)
			)
		)
		(property "Value" "R_75R_0402"
			(at 49.53 193.04 0)
			(effects
				(font
					(size 1.27 1.27)
					(thickness 0.15)
				)
				(justify left bottom)
				(hide yes)
			)
		)
		(property "Footprint" "antmicro-footprints:R_0402_1005Metric"
			(at 46.99 193.04 0)
			(effects
				(font
					(size 1.27 1.27)
					(thickness 0.15)
				)
				(justify left bottom)
				(hide yes)
			)
		)
		(property "Datasheet" "https://www.bourns.com/docs/product-datasheets/cr.pdf"
			(at 44.45 193.04 0)
			(effects
				(font
					(size 1.27 1.27)
					(thickness 0.15)
				)
				(justify left bottom)
				(hide yes)
			)
		)
		(property "Description" "SMD Chip Resistor, 75 ohm, ± 1%, 62.5 mW, 0402 [1005 Metric], Thick Film, General Purpose"
			(at 62.23 213.36 0)
			(effects
				(font
					(size 1.27 1.27)
				)
				(hide yes)
			)
		)
		(property "Manufacturer" "Bourns"
			(at 39.37 193.04 0)
			(effects
				(font
					(size 1.27 1.27)
					(thickness 0.15)
				)
				(justify left bottom)
				(hide yes)
			)
		)
		(property "MPN" "CR0402-FX-75R0GLF"
			(at 41.91 193.04 0)
			(effects
				(font
					(size 1.27 1.27)
					(thickness 0.15)
				)
				(justify left bottom)
				(hide yes)
			)
		)
		(property "Val" "75R"
			(at 64.77 212.0899 90)
			(effects
				(font
					(size 1.27 1.27)
					(thickness 0.15)
				)
				(justify left)
			)
		)
		(property "License" "Apache-2.0"
			(at 36.83 193.04 0)
			(effects
				(font
					(size 1.27 1.27)
					(thickness 0.15)
				)
				(justify left bottom)
				(hide yes)
			)
		)
		(property "Author" "Antmicro"
			(at 34.29 193.04 0)
			(effects
				(font
					(size 1.27 1.27)
					(thickness 0.15)
				)
				(justify left bottom)
				(hide yes)
			)
		)
		(property "Tolerance" "1%"
			(at 52.07 193.04 0)
			(effects
				(font
					(size 1.27 1.27)
				)
				(justify left bottom)
				(hide yes)
			)
		)
		(pin "1"
		)
		(pin "2"
		)
		(instances
			(project "sdi-mipi-video-converter"
				(path ""
					(reference "R52")
					(unit 1)
				)
			)
		)
	)
	(symbol
		(lib_id "antmicropower:GND")
		(at 270.51 257.81 0)
		(unit 1)
		(exclude_from_sim no)
		(in_bom yes)
		(on_board yes)
		(dnp no)
		(fields_autoplaced yes)
		(property "Reference" "#PWR0139"
			(at 279.4 260.35 0)
			(effects
				(font
					(size 1.27 1.27)
					(thickness 0.15)
				)
				(justify left bottom)
				(hide yes)
			)
		)
		(property "Value" "GND"
			(at 270.51 262.89 0)
			(effects
				(font
					(size 1.27 1.27)
					(thickness 0.15)
				)
			)
		)
		(property "Footprint" ""
			(at 279.4 265.43 0)
			(effects
				(font
					(size 1.27 1.27)
					(thickness 0.15)
				)
				(justify left bottom)
				(hide yes)
			)
		)
		(property "Datasheet" ""
			(at 279.4 270.51 0)
			(effects
				(font
					(size 1.27 1.27)
					(thickness 0.15)
				)
				(justify left bottom)
				(hide yes)
			)
		)
		(property "Description" ""
			(at 270.51 257.81 0)
			(effects
				(font
					(size 1.27 1.27)
				)
				(hide yes)
			)
		)
		(property "Author" "Antmicro"
			(at 279.4 265.43 0)
			(effects
				(font
					(size 1.27 1.27)
					(thickness 0.15)
				)
				(justify left bottom)
				(hide yes)
			)
		)
		(property "License" "Apache-2.0"
			(at 279.4 267.97 0)
			(effects
				(font
					(size 1.27 1.27)
					(thickness 0.15)
				)
				(justify left bottom)
				(hide yes)
			)
		)
		(pin "1"
		)
		(instances
			(project "sdi-mipi-video-converter"
				(path ""
					(reference "#PWR0139")
					(unit 1)
				)
			)
		)
	)
	(symbol
		(lib_id "antmicroTestPoints:TP_0.75mm_SMD")
		(at 168.91 187.96 0)
		(unit 1)
		(exclude_from_sim no)
		(in_bom yes)
		(on_board yes)
		(dnp no)
		(fields_autoplaced yes)
		(property "Reference" "TP36"
			(at 173.99 187.9599 0)
			(effects
				(font
					(size 1.27 1.27)
					(thickness 0.15)
				)
				(justify left)
			)
		)
		(property "Value" "TP_0.75mm_SMD"
			(at 186.69 195.58 0)
			(effects
				(font
					(size 1.27 1.27)
					(thickness 0.15)
				)
				(justify left bottom)
				(hide yes)
			)
		)
		(property "Footprint" "antmicro-footprints:TP_SMD_0.75mm"
			(at 186.69 198.12 0)
			(effects
				(font
					(size 1.27 1.27)
					(thickness 0.15)
				)
				(justify left bottom)
				(hide yes)
			)
		)
		(property "Datasheet" ""
			(at 186.69 200.66 0)
			(effects
				(font
					(size 1.27 1.27)
					(thickness 0.15)
				)
				(justify left bottom)
				(hide yes)
			)
		)
		(property "Description" "SMT test point"
			(at 168.91 187.96 0)
			(effects
				(font
					(size 1.27 1.27)
				)
				(hide yes)
			)
		)
		(property "MPN" ""
			(at 186.69 203.2 0)
			(effects
				(font
					(size 1.27 1.27)
					(thickness 0.15)
				)
				(justify left bottom)
				(hide yes)
			)
		)
		(property "Manufacturer" ""
			(at 186.69 205.74 0)
			(effects
				(font
					(size 1.27 1.27)
					(thickness 0.15)
				)
				(justify left bottom)
				(hide yes)
			)
		)
		(property "Author" "Antmicro"
			(at 186.69 208.28 0)
			(effects
				(font
					(size 1.27 1.27)
					(thickness 0.15)
				)
				(justify left bottom)
				(hide yes)
			)
		)
		(property "License" "Apache-2.0"
			(at 186.69 210.82 0)
			(effects
				(font
					(size 1.27 1.27)
					(thickness 0.15)
				)
				(justify left bottom)
				(hide yes)
			)
		)
		(pin "1"
		)
		(instances
			(project "sdi-mipi-video-converter"
				(path ""
					(reference "TP36")
					(unit 1)
				)
			)
		)
	)
	(symbol
		(lib_id "antmicropower:GND")
		(at 262.89 101.6 0)
		(unit 1)
		(exclude_from_sim no)
		(in_bom yes)
		(on_board yes)
		(dnp no)
		(fields_autoplaced yes)
		(property "Reference" "#PWR0141"
			(at 271.78 104.14 0)
			(effects
				(font
					(size 1.27 1.27)
					(thickness 0.15)
				)
				(justify left bottom)
				(hide yes)
			)
		)
		(property "Value" "GND"
			(at 262.89 106.68 0)
			(effects
				(font
					(size 1.27 1.27)
					(thickness 0.15)
				)
			)
		)
		(property "Footprint" ""
			(at 271.78 109.22 0)
			(effects
				(font
					(size 1.27 1.27)
					(thickness 0.15)
				)
				(justify left bottom)
				(hide yes)
			)
		)
		(property "Datasheet" ""
			(at 271.78 114.3 0)
			(effects
				(font
					(size 1.27 1.27)
					(thickness 0.15)
				)
				(justify left bottom)
				(hide yes)
			)
		)
		(property "Description" ""
			(at 262.89 101.6 0)
			(effects
				(font
					(size 1.27 1.27)
				)
				(hide yes)
			)
		)
		(property "Author" "Antmicro"
			(at 271.78 109.22 0)
			(effects
				(font
					(size 1.27 1.27)
					(thickness 0.15)
				)
				(justify left bottom)
				(hide yes)
			)
		)
		(property "License" "Apache-2.0"
			(at 271.78 111.76 0)
			(effects
				(font
					(size 1.27 1.27)
					(thickness 0.15)
				)
				(justify left bottom)
				(hide yes)
			)
		)
		(pin "1"
		)
		(instances
			(project "sdi-mipi-video-converter"
				(path ""
					(reference "#PWR0141")
					(unit 1)
				)
			)
		)
	)
	(symbol
		(lib_id "antmicropower:+3.3V")
		(at 115.57 157.48 0)
		(unit 1)
		(exclude_from_sim no)
		(in_bom yes)
		(on_board yes)
		(dnp no)
		(fields_autoplaced yes)
		(property "Reference" "#PWR0118"
			(at 115.57 161.29 0)
			(effects
				(font
					(size 1.27 1.27)
				)
				(hide yes)
			)
		)
		(property "Value" "+3V3"
			(at 115.57 152.4 0)
			(effects
				(font
					(size 1.27 1.27)
				)
			)
		)
		(property "Footprint" ""
			(at 115.57 157.48 0)
			(effects
				(font
					(size 1.27 1.27)
				)
				(hide yes)
			)
		)
		(property "Datasheet" ""
			(at 115.57 157.48 0)
			(effects
				(font
					(size 1.27 1.27)
				)
				(hide yes)
			)
		)
		(property "Description" ""
			(at 115.57 157.48 0)
			(effects
				(font
					(size 1.27 1.27)
				)
				(hide yes)
			)
		)
		(pin "1"
		)
		(instances
			(project "sdi-mipi-video-converter"
				(path ""
					(reference "#PWR0118")
					(unit 1)
				)
			)
		)
	)
	(symbol
		(lib_id "antmicroTestPoints:TP_0.75mm_SMD")
		(at 168.91 177.8 0)
		(unit 1)
		(exclude_from_sim no)
		(in_bom yes)
		(on_board yes)
		(dnp no)
		(fields_autoplaced yes)
		(property "Reference" "TP32"
			(at 173.99 177.7999 0)
			(effects
				(font
					(size 1.27 1.27)
					(thickness 0.15)
				)
				(justify left)
			)
		)
		(property "Value" "TP_0.75mm_SMD"
			(at 186.69 185.42 0)
			(effects
				(font
					(size 1.27 1.27)
					(thickness 0.15)
				)
				(justify left bottom)
				(hide yes)
			)
		)
		(property "Footprint" "antmicro-footprints:TP_SMD_0.75mm"
			(at 186.69 187.96 0)
			(effects
				(font
					(size 1.27 1.27)
					(thickness 0.15)
				)
				(justify left bottom)
				(hide yes)
			)
		)
		(property "Datasheet" ""
			(at 186.69 190.5 0)
			(effects
				(font
					(size 1.27 1.27)
					(thickness 0.15)
				)
				(justify left bottom)
				(hide yes)
			)
		)
		(property "Description" "SMT test point"
			(at 168.91 177.8 0)
			(effects
				(font
					(size 1.27 1.27)
				)
				(hide yes)
			)
		)
		(property "MPN" ""
			(at 186.69 193.04 0)
			(effects
				(font
					(size 1.27 1.27)
					(thickness 0.15)
				)
				(justify left bottom)
				(hide yes)
			)
		)
		(property "Manufacturer" ""
			(at 186.69 195.58 0)
			(effects
				(font
					(size 1.27 1.27)
					(thickness 0.15)
				)
				(justify left bottom)
				(hide yes)
			)
		)
		(property "Author" "Antmicro"
			(at 186.69 198.12 0)
			(effects
				(font
					(size 1.27 1.27)
					(thickness 0.15)
				)
				(justify left bottom)
				(hide yes)
			)
		)
		(property "License" "Apache-2.0"
			(at 186.69 200.66 0)
			(effects
				(font
					(size 1.27 1.27)
					(thickness 0.15)
				)
				(justify left bottom)
				(hide yes)
			)
		)
		(pin "1"
		)
		(instances
			(project "sdi-mipi-video-converter"
				(path ""
					(reference "TP32")
					(unit 1)
				)
			)
		)
	)
	(symbol
		(lib_id "antmicropower:GND")
		(at 339.09 71.12 0)
		(unit 1)
		(exclude_from_sim no)
		(in_bom yes)
		(on_board yes)
		(dnp no)
		(fields_autoplaced yes)
		(property "Reference" "#PWR0146"
			(at 347.98 73.66 0)
			(effects
				(font
					(size 1.27 1.27)
					(thickness 0.15)
				)
				(justify left bottom)
				(hide yes)
			)
		)
		(property "Value" "GND"
			(at 336.55 72.3899 0)
			(effects
				(font
					(size 1.27 1.27)
					(thickness 0.15)
				)
				(justify right)
			)
		)
		(property "Footprint" ""
			(at 347.98 78.74 0)
			(effects
				(font
					(size 1.27 1.27)
					(thickness 0.15)
				)
				(justify left bottom)
				(hide yes)
			)
		)
		(property "Datasheet" ""
			(at 347.98 83.82 0)
			(effects
				(font
					(size 1.27 1.27)
					(thickness 0.15)
				)
				(justify left bottom)
				(hide yes)
			)
		)
		(property "Description" ""
			(at 339.09 71.12 0)
			(effects
				(font
					(size 1.27 1.27)
				)
				(hide yes)
			)
		)
		(property "Author" "Antmicro"
			(at 347.98 78.74 0)
			(effects
				(font
					(size 1.27 1.27)
					(thickness 0.15)
				)
				(justify left bottom)
				(hide yes)
			)
		)
		(property "License" "Apache-2.0"
			(at 347.98 81.28 0)
			(effects
				(font
					(size 1.27 1.27)
					(thickness 0.15)
				)
				(justify left bottom)
				(hide yes)
			)
		)
		(pin "1"
		)
		(instances
			(project "sdi-mipi-video-converter"
				(path ""
					(reference "#PWR0146")
					(unit 1)
				)
			)
		)
	)
	(symbol
		(lib_id "antmicropower:+1V2")
		(at 247.65 184.15 0)
		(unit 1)
		(exclude_from_sim no)
		(in_bom yes)
		(on_board yes)
		(dnp no)
		(fields_autoplaced yes)
		(property "Reference" "#PWR0121"
			(at 247.65 187.96 0)
			(effects
				(font
					(size 1.27 1.27)
				)
				(hide yes)
			)
		)
		(property "Value" "+1V2"
			(at 247.65 179.07 0)
			(effects
				(font
					(size 1.27 1.27)
				)
			)
		)
		(property "Footprint" ""
			(at 247.65 184.15 0)
			(effects
				(font
					(size 1.27 1.27)
				)
				(hide yes)
			)
		)
		(property "Datasheet" ""
			(at 247.65 184.15 0)
			(effects
				(font
					(size 1.27 1.27)
				)
				(hide yes)
			)
		)
		(property "Description" ""
			(at 247.65 184.15 0)
			(effects
				(font
					(size 1.27 1.27)
				)
				(hide yes)
			)
		)
		(pin "1"
		)
		(instances
			(project "sdi-mipi-video-converter"
				(path ""
					(reference "#PWR0121")
					(unit 1)
				)
			)
		)
	)
	(symbol
		(lib_id "antmicroCapacitorsmisc:C_100n_0201")
		(at 212.09 72.39 90)
		(unit 1)
		(exclude_from_sim no)
		(in_bom yes)
		(on_board yes)
		(dnp no)
		(fields_autoplaced yes)
		(property "Reference" "C115"
			(at 214.63 68.5735 90)
			(effects
				(font
					(size 1.27 1.27)
					(thickness 0.15)
				)
				(justify right)
			)
		)
		(property "Value" "C_100n_0201"
			(at 222.25 52.07 0)
			(effects
				(font
					(size 1.27 1.27)
					(thickness 0.15)
				)
				(justify left bottom)
				(hide yes)
			)
		)
		(property "Footprint" "antmicro-footprints:C_0201"
			(at 224.79 52.07 0)
			(effects
				(font
					(size 1.27 1.27)
					(thickness 0.15)
				)
				(justify left bottom)
				(hide yes)
			)
		)
		(property "Datasheet" "https://www.yageo.com/en/Chart/Download/pdf/CC0201KRX6S5BB104"
			(at 227.33 52.07 0)
			(effects
				(font
					(size 1.27 1.27)
					(thickness 0.15)
				)
				(justify left bottom)
				(hide yes)
			)
		)
		(property "Description" "SMD Multilayer Ceramic Capacitor, 0.1 µF, 6.3 V, 0201 [0603 Metric], ± 10%, X6S, CC Series"
			(at 212.09 72.39 0)
			(effects
				(font
					(size 1.27 1.27)
				)
				(hide yes)
			)
		)
		(property "Manufacturer" "YAGEO"
			(at 232.41 52.07 0)
			(effects
				(font
					(size 1.27 1.27)
					(thickness 0.15)
				)
				(justify left bottom)
				(hide yes)
			)
		)
		(property "MPN" "CC0201KRX6S5BB104"
			(at 229.87 52.07 0)
			(effects
				(font
					(size 1.27 1.27)
					(thickness 0.15)
				)
				(justify left bottom)
				(hide yes)
			)
		)
		(property "Val" "100n"
			(at 214.63 71.1135 90)
			(effects
				(font
					(size 1.27 1.27)
					(thickness 0.15)
				)
				(justify right)
			)
		)
		(property "License" "Apache-2.0"
			(at 234.95 52.07 0)
			(effects
				(font
					(size 1.27 1.27)
					(thickness 0.15)
				)
				(justify left bottom)
				(hide yes)
			)
		)
		(property "Author" "Antmicro"
			(at 237.49 52.07 0)
			(effects
				(font
					(size 1.27 1.27)
					(thickness 0.15)
				)
				(justify left bottom)
				(hide yes)
			)
		)
		(property "Voltage" ""
			(at 240.03 52.07 0)
			(effects
				(font
					(size 1.27 1.27)
				)
				(justify left bottom)
				(hide yes)
			)
		)
		(property "Dielectric" ""
			(at 242.57 52.07 0)
			(effects
				(font
					(size 1.27 1.27)
				)
				(justify left bottom)
				(hide yes)
			)
		)
		(property "Public" "False"
			(at 245.11 52.07 0)
			(effects
				(font
					(size 1.27 1.27)
				)
				(justify left bottom)
				(hide yes)
			)
		)
		(pin "1"
		)
		(pin "2"
		)
		(instances
			(project "sdi-mipi-video-converter"
				(path ""
					(reference "C115")
					(unit 1)
				)
			)
		)
	)
	(symbol
		(lib_id "antmicroResistors0402:R_100k_0402")
		(at 115.57 158.75 90)
		(mirror x)
		(unit 1)
		(exclude_from_sim no)
		(in_bom yes)
		(on_board yes)
		(dnp no)
		(fields_autoplaced yes)
		(property "Reference" "R55"
			(at 118.11 160.0199 90)
			(effects
				(font
					(size 1.27 1.27)
					(thickness 0.15)
				)
				(justify right)
			)
		)
		(property "Value" "R_100k_0402"
			(at 128.27 179.07 0)
			(effects
				(font
					(size 1.27 1.27)
					(thickness 0.15)
				)
				(justify left bottom)
				(hide yes)
			)
		)
		(property "Footprint" "antmicro-footprints:R_0402_1005Metric"
			(at 130.81 179.07 0)
			(effects
				(font
					(size 1.27 1.27)
					(thickness 0.15)
				)
				(justify left bottom)
				(hide yes)
			)
		)
		(property "Datasheet" "https://www.bourns.com/docs/product-datasheets/cr.pdf"
			(at 133.35 179.07 0)
			(effects
				(font
					(size 1.27 1.27)
					(thickness 0.15)
				)
				(justify left bottom)
				(hide yes)
			)
		)
		(property "Description" "SMD Chip Resistor, 100 kohm, ± 1%, 62.5 mW, 0402 [1005 Metric], Thick Film, General Purpose"
			(at 115.57 158.75 0)
			(effects
				(font
					(size 1.27 1.27)
				)
				(hide yes)
			)
		)
		(property "Manufacturer" "Bourns"
			(at 138.43 179.07 0)
			(effects
				(font
					(size 1.27 1.27)
					(thickness 0.15)
				)
				(justify left bottom)
				(hide yes)
			)
		)
		(property "MPN" "CR0402-FX-1003GLF"
			(at 135.89 179.07 0)
			(effects
				(font
					(size 1.27 1.27)
					(thickness 0.15)
				)
				(justify left bottom)
				(hide yes)
			)
		)
		(property "Val" "100k"
			(at 118.11 162.5599 90)
			(effects
				(font
					(size 1.27 1.27)
					(thickness 0.15)
				)
				(justify right)
			)
		)
		(property "License" "Apache-2.0"
			(at 140.97 179.07 0)
			(effects
				(font
					(size 1.27 1.27)
					(thickness 0.15)
				)
				(justify left bottom)
				(hide yes)
			)
		)
		(property "Author" "Antmicro"
			(at 143.51 179.07 0)
			(effects
				(font
					(size 1.27 1.27)
					(thickness 0.15)
				)
				(justify left bottom)
				(hide yes)
			)
		)
		(property "Tolerance" "1%"
			(at 125.73 179.07 0)
			(effects
				(font
					(size 1.27 1.27)
				)
				(justify left bottom)
				(hide yes)
			)
		)
		(pin "1"
		)
		(pin "2"
		)
		(instances
			(project "sdi-mipi-video-converter"
				(path ""
					(reference "R55")
					(unit 1)
				)
			)
		)
	)
	(symbol
		(lib_id "antmicroCapacitors0402:C_10n_0402")
		(at 317.5 82.55 0)
		(mirror x)
		(unit 1)
		(exclude_from_sim no)
		(in_bom yes)
		(on_board yes)
		(dnp no)
		(fields_autoplaced yes)
		(property "Reference" "C76"
			(at 320.0463 76.2 0)
			(effects
				(font
					(size 1.27 1.27)
					(thickness 0.15)
				)
			)
		)
		(property "Value" "C_10n_0402"
			(at 337.82 72.39 0)
			(effects
				(font
					(size 1.27 1.27)
					(thickness 0.15)
				)
				(justify left bottom)
				(hide yes)
			)
		)
		(property "Footprint" "antmicro-footprints:C_0402_1005Metric"
			(at 337.82 69.85 0)
			(effects
				(font
					(size 1.27 1.27)
					(thickness 0.15)
				)
				(justify left bottom)
				(hide yes)
			)
		)
		(property "Datasheet" "https://www.murata.com/products/productdetail?partno=GRM155R71H103KA88%23"
			(at 337.82 67.31 0)
			(effects
				(font
					(size 1.27 1.27)
					(thickness 0.15)
				)
				(justify left bottom)
				(hide yes)
			)
		)
		(property "Description" "SMD Multilayer Ceramic Capacitor, 10000 pF, 50 V, 0402 [1005 Metric], ± 10%, X7R, GRM Series"
			(at 317.5 82.55 0)
			(effects
				(font
					(size 1.27 1.27)
				)
				(hide yes)
			)
		)
		(property "Manufacturer" "Murata"
			(at 337.82 62.23 0)
			(effects
				(font
					(size 1.27 1.27)
					(thickness 0.15)
				)
				(justify left bottom)
				(hide yes)
			)
		)
		(property "MPN" "GRM155R71H103KA88D"
			(at 337.82 64.77 0)
			(effects
				(font
					(size 1.27 1.27)
					(thickness 0.15)
				)
				(justify left bottom)
				(hide yes)
			)
		)
		(property "Val" "10n"
			(at 320.0463 78.74 0)
			(effects
				(font
					(size 1.27 1.27)
					(thickness 0.15)
				)
			)
		)
		(property "License" "Apache-2.0"
			(at 337.82 59.69 0)
			(effects
				(font
					(size 1.27 1.27)
					(thickness 0.15)
				)
				(justify left bottom)
				(hide yes)
			)
		)
		(property "Author" "Antmicro"
			(at 337.82 57.15 0)
			(effects
				(font
					(size 1.27 1.27)
					(thickness 0.15)
				)
				(justify left bottom)
				(hide yes)
			)
		)
		(property "Voltage" "50V"
			(at 337.82 54.61 0)
			(effects
				(font
					(size 1.27 1.27)
				)
				(justify left bottom)
				(hide yes)
			)
		)
		(property "Dielectric" "X7R"
			(at 337.82 52.07 0)
			(effects
				(font
					(size 1.27 1.27)
				)
				(justify left bottom)
				(hide yes)
			)
		)
		(pin "1"
		)
		(pin "2"
		)
		(instances
			(project "sdi-mipi-video-converter"
				(path ""
					(reference "C76")
					(unit 1)
				)
			)
		)
	)
	(symbol
		(lib_id "antmicroResistors0402:R_750R_0402")
		(at 289.56 77.47 270)
		(mirror x)
		(unit 1)
		(exclude_from_sim no)
		(in_bom yes)
		(on_board yes)
		(dnp no)
		(fields_autoplaced yes)
		(property "Reference" "R57"
			(at 292.1 73.6599 90)
			(effects
				(font
					(size 1.27 1.27)
					(thickness 0.15)
				)
				(justify left)
			)
		)
		(property "Value" "R_750R_0402"
			(at 276.86 57.15 0)
			(effects
				(font
					(size 1.27 1.27)
					(thickness 0.15)
				)
				(justify left bottom)
				(hide yes)
			)
		)
		(property "Footprint" "antmicro-footprints:R_0402_1005Metric"
			(at 274.32 57.15 0)
			(effects
				(font
					(size 1.27 1.27)
					(thickness 0.15)
				)
				(justify left bottom)
				(hide yes)
			)
		)
		(property "Datasheet" "https://www.bourns.com/docs/product-datasheets/cr.pdf"
			(at 271.78 57.15 0)
			(effects
				(font
					(size 1.27 1.27)
					(thickness 0.15)
				)
				(justify left bottom)
				(hide yes)
			)
		)
		(property "Description" "SMD Chip Resistor, 750 ohm, ± 1%, 63 mW, 0402 [1005 Metric], Thick Film, General Purpose"
			(at 289.56 77.47 0)
			(effects
				(font
					(size 1.27 1.27)
				)
				(hide yes)
			)
		)
		(property "Manufacturer" "Bourns"
			(at 266.7 57.15 0)
			(effects
				(font
					(size 1.27 1.27)
					(thickness 0.15)
				)
				(justify left bottom)
				(hide yes)
			)
		)
		(property "MPN" "CR0402-FX-7500GLF"
			(at 269.24 57.15 0)
			(effects
				(font
					(size 1.27 1.27)
					(thickness 0.15)
				)
				(justify left bottom)
				(hide yes)
			)
		)
		(property "Val" "750R"
			(at 292.1 76.1999 90)
			(effects
				(font
					(size 1.27 1.27)
					(thickness 0.15)
				)
				(justify left)
			)
		)
		(property "License" "Apache-2.0"
			(at 264.16 57.15 0)
			(effects
				(font
					(size 1.27 1.27)
					(thickness 0.15)
				)
				(justify left bottom)
				(hide yes)
			)
		)
		(property "Author" "Antmicro"
			(at 261.62 57.15 0)
			(effects
				(font
					(size 1.27 1.27)
					(thickness 0.15)
				)
				(justify left bottom)
				(hide yes)
			)
		)
		(property "Tolerance" "1%"
			(at 279.4 57.15 0)
			(effects
				(font
					(size 1.27 1.27)
				)
				(justify left bottom)
				(hide yes)
			)
		)
		(pin "1"
		)
		(pin "2"
		)
		(instances
			(project "sdi-mipi-video-converter"
				(path ""
					(reference "R57")
					(unit 1)
				)
			)
		)
	)
	(symbol
		(lib_id "antmicroResistors0402:R_0R_0402")
		(at 261.62 80.01 270)
		(mirror x)
		(unit 1)
		(exclude_from_sim no)
		(in_bom yes)
		(on_board yes)
		(dnp no)
		(fields_autoplaced yes)
		(property "Reference" "R38"
			(at 259.08 76.1999 90)
			(effects
				(font
					(size 1.27 1.27)
					(thickness 0.15)
				)
				(justify right)
			)
		)
		(property "Value" "R_0R_0402"
			(at 248.92 59.69 0)
			(effects
				(font
					(size 1.27 1.27)
					(thickness 0.15)
				)
				(justify left bottom)
				(hide yes)
			)
		)
		(property "Footprint" "antmicro-footprints:R_0402_1005Metric"
			(at 246.38 59.69 0)
			(effects
				(font
					(size 1.27 1.27)
					(thickness 0.15)
				)
				(justify left bottom)
				(hide yes)
			)
		)
		(property "Datasheet" "https://industrial.panasonic.com/cdbs/www-data/pdf/RDA0000/AOA0000C301.pdf"
			(at 243.84 59.69 0)
			(effects
				(font
					(size 1.27 1.27)
					(thickness 0.15)
				)
				(justify left bottom)
				(hide yes)
			)
		)
		(property "Description" "SMD Chip Resistor, Jumper, 0 ohm, 100 mW, 0402 [1005 Metric], Thick Film, General Purpose"
			(at 261.62 80.01 0)
			(effects
				(font
					(size 1.27 1.27)
				)
				(hide yes)
			)
		)
		(property "Manufacturer" "Panasonic"
			(at 238.76 59.69 0)
			(effects
				(font
					(size 1.27 1.27)
					(thickness 0.15)
				)
				(justify left bottom)
				(hide yes)
			)
		)
		(property "MPN" "ERJ2GE0R00X"
			(at 241.3 59.69 0)
			(effects
				(font
					(size 1.27 1.27)
					(thickness 0.15)
				)
				(justify left bottom)
				(hide yes)
			)
		)
		(property "Val" "0R"
			(at 259.08 78.7399 90)
			(effects
				(font
					(size 1.27 1.27)
					(thickness 0.15)
				)
				(justify right)
			)
		)
		(property "License" "Apache-2.0"
			(at 236.22 59.69 0)
			(effects
				(font
					(size 1.27 1.27)
					(thickness 0.15)
				)
				(justify left bottom)
				(hide yes)
			)
		)
		(property "Author" "Antmicro"
			(at 233.68 59.69 0)
			(effects
				(font
					(size 1.27 1.27)
					(thickness 0.15)
				)
				(justify left bottom)
				(hide yes)
			)
		)
		(property "Tolerance" "~"
			(at 251.46 59.69 0)
			(effects
				(font
					(size 1.27 1.27)
				)
				(justify left bottom)
				(hide yes)
			)
		)
		(property "Current" "1A"
			(at 231.14 59.69 0)
			(effects
				(font
					(size 1.27 1.27)
					(thickness 0.15)
				)
				(justify left bottom)
				(hide yes)
			)
		)
		(pin "1"
		)
		(pin "2"
		)
		(instances
			(project "sdi-mipi-video-converter"
				(path ""
					(reference "R38")
					(unit 1)
				)
			)
		)
	)
	(symbol
		(lib_id "antmicroTestPoints:TP_0.75mm_SMD")
		(at 168.91 203.2 0)
		(unit 1)
		(exclude_from_sim no)
		(in_bom yes)
		(on_board yes)
		(dnp no)
		(fields_autoplaced yes)
		(property "Reference" "TP42"
			(at 173.99 203.1999 0)
			(effects
				(font
					(size 1.27 1.27)
					(thickness 0.15)
				)
				(justify left)
			)
		)
		(property "Value" "TP_0.75mm_SMD"
			(at 186.69 210.82 0)
			(effects
				(font
					(size 1.27 1.27)
					(thickness 0.15)
				)
				(justify left bottom)
				(hide yes)
			)
		)
		(property "Footprint" "antmicro-footprints:TP_SMD_0.75mm"
			(at 186.69 213.36 0)
			(effects
				(font
					(size 1.27 1.27)
					(thickness 0.15)
				)
				(justify left bottom)
				(hide yes)
			)
		)
		(property "Datasheet" ""
			(at 186.69 215.9 0)
			(effects
				(font
					(size 1.27 1.27)
					(thickness 0.15)
				)
				(justify left bottom)
				(hide yes)
			)
		)
		(property "Description" "SMT test point"
			(at 168.91 203.2 0)
			(effects
				(font
					(size 1.27 1.27)
				)
				(hide yes)
			)
		)
		(property "MPN" ""
			(at 186.69 218.44 0)
			(effects
				(font
					(size 1.27 1.27)
					(thickness 0.15)
				)
				(justify left bottom)
				(hide yes)
			)
		)
		(property "Manufacturer" ""
			(at 186.69 220.98 0)
			(effects
				(font
					(size 1.27 1.27)
					(thickness 0.15)
				)
				(justify left bottom)
				(hide yes)
			)
		)
		(property "Author" "Antmicro"
			(at 186.69 223.52 0)
			(effects
				(font
					(size 1.27 1.27)
					(thickness 0.15)
				)
				(justify left bottom)
				(hide yes)
			)
		)
		(property "License" "Apache-2.0"
			(at 186.69 226.06 0)
			(effects
				(font
					(size 1.27 1.27)
					(thickness 0.15)
				)
				(justify left bottom)
				(hide yes)
			)
		)
		(pin "1"
		)
		(instances
			(project "sdi-mipi-video-converter"
				(path ""
					(reference "TP42")
					(unit 1)
				)
			)
		)
	)
	(symbol
		(lib_id "antmicroCapacitors0402:C_1u_0402")
		(at 88.9 199.39 0)
		(mirror y)
		(unit 1)
		(exclude_from_sim no)
		(in_bom yes)
		(on_board yes)
		(dnp no)
		(fields_autoplaced yes)
		(property "Reference" "C53"
			(at 86.3536 193.04 0)
			(effects
				(font
					(size 1.27 1.27)
					(thickness 0.15)
				)
			)
		)
		(property "Value" "C_1u_0402"
			(at 68.58 209.55 0)
			(effects
				(font
					(size 1.27 1.27)
					(thickness 0.15)
				)
				(justify left bottom)
				(hide yes)
			)
		)
		(property "Footprint" "antmicro-footprints:C_0402_1005Metric"
			(at 68.58 212.09 0)
			(effects
				(font
					(size 1.27 1.27)
					(thickness 0.15)
				)
				(justify left bottom)
				(hide yes)
			)
		)
		(property "Datasheet" "https://product.tdk.com/en/search/capacitor/ceramic/mlcc/info?part_no=C1005X6S1A105K050BC"
			(at 68.58 214.63 0)
			(effects
				(font
					(size 1.27 1.27)
					(thickness 0.15)
				)
				(justify left bottom)
				(hide yes)
			)
		)
		(property "Description" "SMD Multilayer Ceramic Capacitor, 1 µF, 10 V, 0402 [1005 Metric], ± 10%, X6S, C"
			(at 88.9 199.39 0)
			(effects
				(font
					(size 1.27 1.27)
				)
				(hide yes)
			)
		)
		(property "Manufacturer" "TDK"
			(at 68.58 219.71 0)
			(effects
				(font
					(size 1.27 1.27)
					(thickness 0.15)
				)
				(justify left bottom)
				(hide yes)
			)
		)
		(property "MPN" "C1005X6S1A105K050BC"
			(at 68.58 217.17 0)
			(effects
				(font
					(size 1.27 1.27)
					(thickness 0.15)
				)
				(justify left bottom)
				(hide yes)
			)
		)
		(property "Val" "1u"
			(at 86.3536 195.58 0)
			(effects
				(font
					(size 1.27 1.27)
					(thickness 0.15)
				)
			)
		)
		(property "License" "Apache-2.0"
			(at 68.58 222.25 0)
			(effects
				(font
					(size 1.27 1.27)
					(thickness 0.15)
				)
				(justify left bottom)
				(hide yes)
			)
		)
		(property "Author" "Antmicro"
			(at 68.58 224.79 0)
			(effects
				(font
					(size 1.27 1.27)
					(thickness 0.15)
				)
				(justify left bottom)
				(hide yes)
			)
		)
		(property "Voltage" ""
			(at 68.58 227.33 0)
			(effects
				(font
					(size 1.27 1.27)
				)
				(justify left bottom)
				(hide yes)
			)
		)
		(property "Dielectric" ""
			(at 68.58 229.87 0)
			(effects
				(font
					(size 1.27 1.27)
				)
				(justify left bottom)
				(hide yes)
			)
		)
		(pin "1"
		)
		(pin "2"
		)
		(instances
			(project "sdi-mipi-video-converter"
				(path ""
					(reference "C53")
					(unit 1)
				)
			)
		)
	)
)
